(kicad_sch
	(version 20250114)
	(generator "eeschema")
	(generator_version "9.0")
	(paper "A3")
	(title_block
		(title "RDIMM DDR5 Tester")
		(date "2026-05-21")
		(rev "2.2.0")
		(company "Antmicro")
		(comment 1 "www.antmicro.com")
		(comment 2 "Antmicro")
	)
	(text "Configuration Modes"
		(exclude_from_sim no)
		(at 302.895 182.88 0)
		(effects
			(font
				(size 2 2)
				(thickness 0.5994)
				(bold yes)
			)
			(justify left bottom)
		)
	)
	(text "LDO"
		(exclude_from_sim no)
		(at 151.13 19.05 0)
		(effects
			(font
				(size 2 2)
				(thickness 0.5994)
				(bold yes)
			)
			(justify left bottom)
		)
	)
	(text "1V25"
		(exclude_from_sim no)
		(at 240.03 48.26 0)
		(effects
			(font
				(size 1.27 1.27)
			)
			(justify left bottom)
		)
	)
	(text "Pull-ups"
		(exclude_from_sim no)
		(at 151.13 97.79 0)
		(effects
			(font
				(size 2 2)
				(thickness 0.5994)
				(bold yes)
			)
			(justify left bottom)
		)
	)
	(text "JTAG Connector\n"
		(exclude_from_sim no)
		(at 303.53 20.32 0)
		(effects
			(font
				(size 2 2)
				(thickness 0.5994)
				(bold yes)
			)
			(justify left bottom)
		)
	)
	(text "000\n001\n010\n100\n101\n110\n111"
		(exclude_from_sim no)
		(at 387.35 226.695 0)
		(effects
			(font
				(size 1.27 1.27)
			)
			(justify left bottom)
		)
	)
	(text "Probes"
		(exclude_from_sim no)
		(at 302.26 97.79 0)
		(effects
			(font
				(size 2 2)
				(thickness 0.5994)
				(bold yes)
			)
			(justify left bottom)
		)
	)
	(text "FPGA BANK 0"
		(exclude_from_sim no)
		(at 15.24 19.685 0)
		(effects
			(font
				(size 2.54 2.54)
				(thickness 0.5994)
				(bold yes)
			)
			(justify left bottom)
		)
	)
	(text "MODE[2:0]"
		(exclude_from_sim no)
		(at 387.223 211.836 0)
		(effects
			(font
				(size 1.27 1.27)
			)
			(justify left bottom)
		)
	)
	(text "I2C: 0x4C"
		(exclude_from_sim no)
		(at 91.186 242.824 0)
		(effects
			(font
				(size 1.27 1.27)
			)
			(justify left bottom)
		)
	)
	(text "Temp sensor"
		(exclude_from_sim no)
		(at 15.24 182.88 0)
		(effects
			(font
				(size 2 2)
				(thickness 0.5994)
				(bold yes)
			)
			(justify left bottom)
		)
	)
	(text "Config. mode"
		(exclude_from_sim no)
		(at 368.427 211.836 0)
		(effects
			(font
				(size 1.27 1.27)
			)
			(justify left bottom)
		)
	)
	(text "Compatible with Xilinx Platform Cable"
		(exclude_from_sim no)
		(at 337.82 72.39 0)
		(effects
			(font
				(size 1.27 1.27)
			)
			(justify left bottom)
		)
	)
	(text "Master Serial\nMaster SPI\nMaster BPI\nMaster SelectMAP\nJTAG\nSlave SelectMAP\nSlave Serial"
		(exclude_from_sim no)
		(at 368.3 226.695 0)
		(effects
			(font
				(size 1.27 1.27)
			)
			(justify left bottom)
		)
	)
	(text "For details, see UG570"
		(exclude_from_sim no)
		(at 370.84 232.41 0)
		(effects
			(font
				(size 1.27 1.27)
			)
			(justify left bottom)
		)
	)
	(text "VCCINT"
		(exclude_from_sim no)
		(at 350.52 113.03 0)
		(effects
			(font
				(size 1.27 1.27)
			)
			(justify left bottom)
		)
	)
	(text "STATUS LEDs"
		(exclude_from_sim no)
		(at 151.13 184.15 0)
		(effects
			(font
				(size 2 2)
				(thickness 0.4)
				(bold yes)
			)
			(justify left bottom)
		)
	)
	(junction
		(at 220.98 151.13)
		(diameter 0)
		(color 0 0 0 0)
	)
	(junction
		(at 346.71 209.55)
		(diameter 0)
		(color 0 0 0 0)
	)
	(junction
		(at 195.58 48.26)
		(diameter 0)
		(color 0 0 0 0)
	)
	(junction
		(at 231.14 59.69)
		(diameter 0)
		(color 0 0 0 0)
	)
	(junction
		(at 334.01 135.89)
		(diameter 0)
		(color 0 0 0 0)
	)
	(junction
		(at 213.36 115.57)
		(diameter 0)
		(color 0 0 0 0)
	)
	(junction
		(at 69.85 113.03)
		(diameter 0)
		(color 0 0 0 0)
	)
	(junction
		(at 353.06 135.89)
		(diameter 0)
		(color 0 0 0 0)
	)
	(junction
		(at 231.14 48.26)
		(diameter 0)
		(color 0 0 0 0)
	)
	(junction
		(at 322.58 43.18)
		(diameter 0)
		(color 0 0 0 0)
	)
	(junction
		(at 322.58 45.72)
		(diameter 0)
		(color 0 0 0 0)
	)
	(junction
		(at 322.58 53.34)
		(diameter 0)
		(color 0 0 0 0)
	)
	(junction
		(at 322.58 50.8)
		(diameter 0)
		(color 0 0 0 0)
	)
	(junction
		(at 322.58 55.88)
		(diameter 0)
		(color 0 0 0 0)
	)
	(junction
		(at 63.5 234.95)
		(diameter 0)
		(color 0 0 0 0)
	)
	(junction
		(at 54.61 237.49)
		(diameter 0)
		(color 0 0 0 0)
	)
	(junction
		(at 220.98 115.57)
		(diameter 0)
		(color 0 0 0 0)
	)
	(junction
		(at 220.98 133.35)
		(diameter 0)
		(color 0 0 0 0)
	)
	(junction
		(at 208.28 133.35)
		(diameter 0)
		(color 0 0 0 0)
	)
	(junction
		(at 80.01 111.76)
		(diameter 0)
		(color 0 0 0 0)
	)
	(junction
		(at 322.58 48.26)
		(diameter 0)
		(color 0 0 0 0)
	)
	(junction
		(at 69.85 123.19)
		(diameter 0)
		(color 0 0 0 0)
	)
	(junction
		(at 220.98 138.43)
		(diameter 0)
		(color 0 0 0 0)
	)
	(no_connect
		(at 336.55 55.88)
	)
	(no_connect
		(at 336.55 53.34)
	)
	(bus_entry
		(at 45.72 95.25)
		(size 1.27 1.27)
		(stroke
			(width 0)
			(type default)
		)
	)
	(bus_entry
		(at 73.66 231.14)
		(size 1.27 1.27)
		(stroke
			(width 0)
			(type default)
		)
	)
	(bus_entry
		(at 45.72 97.79)
		(size 1.27 1.27)
		(stroke
			(width 0)
			(type default)
		)
	)
	(bus_entry
		(at 45.72 100.33)
		(size 1.27 1.27)
		(stroke
			(width 0)
			(type default)
		)
	)
	(bus_entry
		(at 45.72 102.87)
		(size 1.27 1.27)
		(stroke
			(width 0)
			(type default)
		)
	)
	(bus_entry
		(at 45.72 69.85)
		(size 1.27 1.27)
		(stroke
			(width 0)
			(type default)
		)
	)
	(bus_entry
		(at 67.31 88.9)
		(size -2.54 -2.54)
		(stroke
			(width 0)
			(type default)
		)
	)
	(bus_entry
		(at 67.31 83.82)
		(size -2.54 -2.54)
		(stroke
			(width 0)
			(type default)
		)
	)
	(bus_entry
		(at 73.66 228.6)
		(size 1.27 1.27)
		(stroke
			(width 0)
			(type default)
		)
	)
	(bus_entry
		(at 45.72 64.77)
		(size 1.27 1.27)
		(stroke
			(width 0)
			(type default)
		)
	)
	(bus_entry
		(at 67.31 91.44)
		(size -2.54 -2.54)
		(stroke
			(width 0)
			(type default)
		)
	)
	(bus_entry
		(at 67.31 86.36)
		(size -2.54 -2.54)
		(stroke
			(width 0)
			(type default)
		)
	)
	(wire
		(pts
			(xy 80.01 53.34) (xy 81.28 53.34)
		)
		(stroke
			(width 0)
			(type default)
		)
	)
	(wire
		(pts
			(xy 205.74 52.07) (xy 208.28 52.07)
		)
		(stroke
			(width 0)
			(type default)
		)
	)
	(wire
		(pts
			(xy 326.39 55.88) (xy 322.58 55.88)
		)
		(stroke
			(width 0)
			(type default)
		)
	)
	(wire
		(pts
			(xy 334.01 138.43) (xy 334.01 135.89)
		)
		(stroke
			(width 0)
			(type default)
		)
	)
	(wire
		(pts
			(xy 335.28 226.06) (xy 354.33 226.06)
		)
		(stroke
			(width 0)
			(type default)
		)
	)
	(wire
		(pts
			(xy 322.58 48.26) (xy 322.58 50.8)
		)
		(stroke
			(width 0)
			(type default)
		)
	)
	(bus
		(pts
			(xy 45.72 95.25) (xy 45.72 97.79)
		)
		(stroke
			(width 0)
			(type default)
		)
	)
	(wire
		(pts
			(xy 251.46 52.07) (xy 259.08 52.07)
		)
		(stroke
			(width 0)
			(type default)
		)
	)
	(wire
		(pts
			(xy 336.55 40.64) (xy 341.63 40.64)
		)
		(stroke
			(width 0)
			(type default)
		)
	)
	(wire
		(pts
			(xy 182.88 213.36) (xy 182.88 217.17)
		)
		(stroke
			(width 0)
			(type default)
		)
	)
	(wire
		(pts
			(xy 231.14 48.26) (xy 245.11 48.26)
		)
		(stroke
			(width 0)
			(type default)
		)
	)
	(wire
		(pts
			(xy 63.5 113.03) (xy 63.5 116.84)
		)
		(stroke
			(width 0)
			(type default)
		)
	)
	(wire
		(pts
			(xy 69.85 113.03) (xy 69.85 115.57)
		)
		(stroke
			(width 0)
			(type default)
		)
	)
	(wire
		(pts
			(xy 106.68 237.49) (xy 107.95 237.49)
		)
		(stroke
			(width 0)
			(type default)
		)
	)
	(wire
		(pts
			(xy 251.46 48.26) (xy 259.08 48.26)
		)
		(stroke
			(width 0)
			(type default)
		)
	)
	(wire
		(pts
			(xy 67.31 86.36) (xy 81.28 86.36)
		)
		(stroke
			(width 0)
			(type default)
		)
	)
	(wire
		(pts
			(xy 63.5 224.79) (xy 63.5 226.06)
		)
		(stroke
			(width 0)
			(type default)
		)
	)
	(wire
		(pts
			(xy 223.52 151.13) (xy 223.52 149.86)
		)
		(stroke
			(width 0)
			(type default)
		)
	)
	(wire
		(pts
			(xy 69.85 120.65) (xy 69.85 123.19)
		)
		(stroke
			(width 0)
			(type default)
		)
	)
	(wire
		(pts
			(xy 334.01 135.89) (xy 345.44 135.89)
		)
		(stroke
			(width 0)
			(type default)
		)
	)
	(polyline
		(pts
			(xy 367.03 212.09) (xy 397.51 212.09)
		)
		(stroke
			(width 0.1016)
			(type solid)
		)
	)
	(polyline
		(pts
			(xy 387.35 209.55) (xy 387.35 227.33)
		)
		(stroke
			(width 0.1016)
			(type solid)
		)
	)
	(wire
		(pts
			(xy 220.98 133.35) (xy 220.98 138.43)
		)
		(stroke
			(width 0)
			(type default)
		)
	)
	(wire
		(pts
			(xy 224.79 242.57) (xy 224.79 243.84)
		)
		(stroke
			(width 0)
			(type default)
		)
	)
	(wire
		(pts
			(xy 326.39 48.26) (xy 322.58 48.26)
		)
		(stroke
			(width 0)
			(type default)
		)
	)
	(wire
		(pts
			(xy 46.99 71.12) (xy 81.28 71.12)
		)
		(stroke
			(width 0)
			(type default)
		)
	)
	(wire
		(pts
			(xy 354.33 209.55) (xy 346.71 209.55)
		)
		(stroke
			(width 0)
			(type default)
		)
	)
	(wire
		(pts
			(xy 326.39 53.34) (xy 322.58 53.34)
		)
		(stroke
			(width 0)
			(type default)
		)
	)
	(wire
		(pts
			(xy 54.61 237.49) (xy 54.61 231.14)
		)
		(stroke
			(width 0)
			(type default)
		)
	)
	(wire
		(pts
			(xy 224.79 222.25) (xy 224.79 223.52)
		)
		(stroke
			(width 0)
			(type default)
		)
	)
	(wire
		(pts
			(xy 267.97 242.57) (xy 267.97 243.84)
		)
		(stroke
			(width 0)
			(type default)
		)
	)
	(wire
		(pts
			(xy 336.55 50.8) (xy 347.98 50.8)
		)
		(stroke
			(width 0)
			(type default)
		)
	)
	(wire
		(pts
			(xy 213.36 114.3) (xy 213.36 115.57)
		)
		(stroke
			(width 0)
			(type default)
		)
	)
	(wire
		(pts
			(xy 67.31 91.44) (xy 81.28 91.44)
		)
		(stroke
			(width 0)
			(type default)
		)
	)
	(wire
		(pts
			(xy 231.14 57.15) (xy 231.14 59.69)
		)
		(stroke
			(width 0)
			(type default)
		)
	)
	(wire
		(pts
			(xy 182.88 222.25) (xy 182.88 223.52)
		)
		(stroke
			(width 0)
			(type default)
		)
	)
	(wire
		(pts
			(xy 31.75 232.41) (xy 31.75 233.68)
		)
		(stroke
			(width 0)
			(type default)
		)
	)
	(wire
		(pts
			(xy 46.99 124.46) (xy 81.28 124.46)
		)
		(stroke
			(width 0)
			(type default)
		)
	)
	(wire
		(pts
			(xy 322.58 43.18) (xy 322.58 45.72)
		)
		(stroke
			(width 0)
			(type default)
		)
	)
	(wire
		(pts
			(xy 68.58 63.5) (xy 81.28 63.5)
		)
		(stroke
			(width 0)
			(type default)
		)
	)
	(polyline
		(pts
			(xy 147.32 91.44) (xy 407.67 91.44)
		)
		(stroke
			(width 0)
			(type default)
		)
	)
	(wire
		(pts
			(xy 46.99 237.49) (xy 54.61 237.49)
		)
		(stroke
			(width 0)
			(type default)
		)
	)
	(wire
		(pts
			(xy 68.58 76.2) (xy 81.28 76.2)
		)
		(stroke
			(width 0)
			(type default)
		)
	)
	(wire
		(pts
			(xy 77.47 119.38) (xy 81.28 119.38)
		)
		(stroke
			(width 0)
			(type default)
		)
	)
	(wire
		(pts
			(xy 220.98 115.57) (xy 220.98 119.38)
		)
		(stroke
			(width 0)
			(type default)
		)
	)
	(wire
		(pts
			(xy 354.33 212.09) (xy 354.33 209.55)
		)
		(stroke
			(width 0)
			(type default)
		)
	)
	(wire
		(pts
			(xy 384.81 53.34) (xy 384.81 58.42)
		)
		(stroke
			(width 0)
			(type default)
		)
	)
	(wire
		(pts
			(xy 77.47 116.84) (xy 77.47 113.03)
		)
		(stroke
			(width 0)
			(type default)
		)
	)
	(wire
		(pts
			(xy 220.98 151.13) (xy 223.52 151.13)
		)
		(stroke
			(width 0)
			(type default)
		)
	)
	(wire
		(pts
			(xy 224.79 229.87) (xy 224.79 228.6)
		)
		(stroke
			(width 0)
			(type default)
		)
	)
	(wire
		(pts
			(xy 31.75 224.79) (xy 31.75 227.33)
		)
		(stroke
			(width 0)
			(type default)
		)
	)
	(wire
		(pts
			(xy 69.85 123.19) (xy 77.47 123.19)
		)
		(stroke
			(width 0)
			(type default)
		)
	)
	(wire
		(pts
			(xy 322.58 55.88) (xy 322.58 60.96)
		)
		(stroke
			(width 0)
			(type default)
		)
	)
	(wire
		(pts
			(xy 220.98 149.86) (xy 220.98 151.13)
		)
		(stroke
			(width 0)
			(type default)
		)
	)
	(wire
		(pts
			(xy 195.58 48.26) (xy 195.58 50.8)
		)
		(stroke
			(width 0)
			(type default)
		)
	)
	(wire
		(pts
			(xy 337.82 209.55) (xy 337.82 212.09)
		)
		(stroke
			(width 0)
			(type default)
		)
	)
	(wire
		(pts
			(xy 67.31 88.9) (xy 81.28 88.9)
		)
		(stroke
			(width 0)
			(type default)
		)
	)
	(wire
		(pts
			(xy 46.99 104.14) (xy 81.28 104.14)
		)
		(stroke
			(width 0)
			(type default)
		)
	)
	(bus
		(pts
			(xy 45.72 69.85) (xy 45.72 95.25)
		)
		(stroke
			(width 0)
			(type default)
		)
	)
	(wire
		(pts
			(xy 205.74 53.34) (xy 205.74 52.07)
		)
		(stroke
			(width 0)
			(type default)
		)
	)
	(wire
		(pts
			(xy 68.58 78.74) (xy 81.28 78.74)
		)
		(stroke
			(width 0)
			(type default)
		)
	)
	(wire
		(pts
			(xy 77.47 123.19) (xy 77.47 119.38)
		)
		(stroke
			(width 0)
			(type default)
		)
	)
	(wire
		(pts
			(xy 195.58 48.26) (xy 208.28 48.26)
		)
		(stroke
			(width 0)
			(type default)
		)
	)
	(wire
		(pts
			(xy 63.5 113.03) (xy 69.85 113.03)
		)
		(stroke
			(width 0)
			(type default)
		)
	)
	(wire
		(pts
			(xy 213.36 119.38) (xy 213.36 115.57)
		)
		(stroke
			(width 0)
			(type default)
		)
	)
	(wire
		(pts
			(xy 106.68 227.33) (xy 125.73 227.33)
		)
		(stroke
			(width 0)
			(type default)
		)
	)
	(wire
		(pts
			(xy 313.69 223.52) (xy 313.69 234.95)
		)
		(stroke
			(width 0)
			(type default)
		)
	)
	(wire
		(pts
			(xy 326.39 43.18) (xy 322.58 43.18)
		)
		(stroke
			(width 0)
			(type default)
		)
	)
	(wire
		(pts
			(xy 382.27 48.26) (xy 391.16 48.26)
		)
		(stroke
			(width 0)
			(type default)
		)
	)
	(wire
		(pts
			(xy 46.99 119.38) (xy 63.5 119.38)
		)
		(stroke
			(width 0)
			(type default)
		)
	)
	(wire
		(pts
			(xy 255.27 238.76) (xy 260.35 238.76)
		)
		(stroke
			(width 0)
			(type default)
		)
	)
	(wire
		(pts
			(xy 46.99 127) (xy 81.28 127)
		)
		(stroke
			(width 0)
			(type default)
		)
	)
	(bus
		(pts
			(xy 45.72 100.33) (xy 45.72 102.87)
		)
		(stroke
			(width 0)
			(type default)
		)
	)
	(wire
		(pts
			(xy 209.55 238.76) (xy 217.17 238.76)
		)
		(stroke
			(width 0)
			(type default)
		)
	)
	(wire
		(pts
			(xy 182.88 229.87) (xy 182.88 228.6)
		)
		(stroke
			(width 0)
			(type default)
		)
	)
	(bus
		(pts
			(xy 44.45 60.96) (xy 45.72 62.23)
		)
		(stroke
			(width 0)
			(type default)
		)
	)
	(wire
		(pts
			(xy 87.63 220.98) (xy 87.63 224.79)
		)
		(stroke
			(width 0)
			(type default)
		)
	)
	(bus
		(pts
			(xy 45.72 64.77) (xy 45.72 69.85)
		)
		(stroke
			(width 0)
			(type default)
		)
	)
	(wire
		(pts
			(xy 46.99 101.6) (xy 81.28 101.6)
		)
		(stroke
			(width 0)
			(type default)
		)
	)
	(wire
		(pts
			(xy 208.28 133.35) (xy 187.96 133.35)
		)
		(stroke
			(width 0)
			(type default)
		)
	)
	(polyline
		(pts
			(xy 12.7 176.53) (xy 408.94 176.53)
		)
		(stroke
			(width 0)
			(type default)
		)
	)
	(wire
		(pts
			(xy 229.87 119.38) (xy 229.87 115.57)
		)
		(stroke
			(width 0)
			(type default)
		)
	)
	(polyline
		(pts
			(xy 299.72 12.7) (xy 299.72 252.73)
		)
		(stroke
			(width 0)
			(type default)
		)
	)
	(wire
		(pts
			(xy 80.01 109.22) (xy 80.01 111.76)
		)
		(stroke
			(width 0)
			(type default)
		)
	)
	(wire
		(pts
			(xy 231.14 59.69) (xy 243.84 59.69)
		)
		(stroke
			(width 0)
			(type default)
		)
	)
	(wire
		(pts
			(xy 208.28 152.4) (xy 208.28 146.05)
		)
		(stroke
			(width 0)
			(type default)
		)
	)
	(wire
		(pts
			(xy 353.06 130.81) (xy 353.06 135.89)
		)
		(stroke
			(width 0)
			(type default)
		)
	)
	(wire
		(pts
			(xy 63.5 234.95) (xy 88.9 234.95)
		)
		(stroke
			(width 0)
			(type default)
		)
	)
	(wire
		(pts
			(xy 382.27 50.8) (xy 391.16 50.8)
		)
		(stroke
			(width 0)
			(type default)
		)
	)
	(wire
		(pts
			(xy 322.58 40.64) (xy 322.58 43.18)
		)
		(stroke
			(width 0)
			(type default)
		)
	)
	(wire
		(pts
			(xy 74.93 232.41) (xy 88.9 232.41)
		)
		(stroke
			(width 0)
			(type default)
		)
	)
	(wire
		(pts
			(xy 80.01 111.76) (xy 81.28 111.76)
		)
		(stroke
			(width 0)
			(type default)
		)
	)
	(wire
		(pts
			(xy 107.95 237.49) (xy 107.95 238.76)
		)
		(stroke
			(width 0)
			(type default)
		)
	)
	(wire
		(pts
			(xy 382.27 45.72) (xy 391.16 45.72)
		)
		(stroke
			(width 0)
			(type default)
		)
	)
	(wire
		(pts
			(xy 327.66 220.98) (xy 337.82 220.98)
		)
		(stroke
			(width 0)
			(type default)
		)
	)
	(wire
		(pts
			(xy 341.63 40.64) (xy 341.63 36.83)
		)
		(stroke
			(width 0)
			(type default)
		)
	)
	(wire
		(pts
			(xy 267.97 229.87) (xy 267.97 228.6)
		)
		(stroke
			(width 0)
			(type default)
		)
	)
	(wire
		(pts
			(xy 224.79 213.36) (xy 224.79 217.17)
		)
		(stroke
			(width 0)
			(type default)
		)
	)
	(bus
		(pts
			(xy 41.91 60.96) (xy 44.45 60.96)
		)
		(stroke
			(width 0)
			(type default)
		)
	)
	(wire
		(pts
			(xy 354.33 217.17) (xy 354.33 226.06)
		)
		(stroke
			(width 0)
			(type default)
		)
	)
	(wire
		(pts
			(xy 346.71 209.55) (xy 337.82 209.55)
		)
		(stroke
			(width 0)
			(type default)
		)
	)
	(wire
		(pts
			(xy 326.39 40.64) (xy 322.58 40.64)
		)
		(stroke
			(width 0)
			(type default)
		)
	)
	(bus
		(pts
			(xy 45.72 97.79) (xy 45.72 100.33)
		)
		(stroke
			(width 0)
			(type default)
		)
	)
	(wire
		(pts
			(xy 229.87 115.57) (xy 220.98 115.57)
		)
		(stroke
			(width 0)
			(type default)
		)
	)
	(bus
		(pts
			(xy 71.12 213.36) (xy 73.66 213.36)
		)
		(stroke
			(width 0)
			(type default)
		)
	)
	(polyline
		(pts
			(xy 147.32 12.7) (xy 147.32 284.48)
		)
		(stroke
			(width 0)
			(type default)
		)
	)
	(wire
		(pts
			(xy 223.52 138.43) (xy 220.98 138.43)
		)
		(stroke
			(width 0)
			(type default)
		)
	)
	(wire
		(pts
			(xy 313.69 223.52) (xy 334.01 223.52)
		)
		(stroke
			(width 0)
			(type default)
		)
	)
	(wire
		(pts
			(xy 223.52 139.7) (xy 223.52 138.43)
		)
		(stroke
			(width 0)
			(type default)
		)
	)
	(bus
		(pts
			(xy 64.77 86.36) (xy 64.77 88.9)
		)
		(stroke
			(width 0)
			(type default)
		)
	)
	(wire
		(pts
			(xy 334.01 130.81) (xy 334.01 135.89)
		)
		(stroke
			(width 0)
			(type default)
		)
	)
	(wire
		(pts
			(xy 54.61 224.79) (xy 54.61 226.06)
		)
		(stroke
			(width 0)
			(type default)
		)
	)
	(wire
		(pts
			(xy 326.39 45.72) (xy 322.58 45.72)
		)
		(stroke
			(width 0)
			(type default)
		)
	)
	(wire
		(pts
			(xy 195.58 55.88) (xy 195.58 58.42)
		)
		(stroke
			(width 0)
			(type default)
		)
	)
	(wire
		(pts
			(xy 46.99 66.04) (xy 81.28 66.04)
		)
		(stroke
			(width 0)
			(type default)
		)
	)
	(wire
		(pts
			(xy 382.27 43.18) (xy 391.16 43.18)
		)
		(stroke
			(width 0)
			(type default)
		)
	)
	(wire
		(pts
			(xy 46.99 96.52) (xy 81.28 96.52)
		)
		(stroke
			(width 0)
			(type default)
		)
	)
	(wire
		(pts
			(xy 46.99 234.95) (xy 63.5 234.95)
		)
		(stroke
			(width 0)
			(type default)
		)
	)
	(bus
		(pts
			(xy 63.5 77.47) (xy 64.77 78.74)
		)
		(stroke
			(width 0)
			(type default)
		)
	)
	(wire
		(pts
			(xy 322.58 53.34) (xy 322.58 55.88)
		)
		(stroke
			(width 0)
			(type default)
		)
	)
	(wire
		(pts
			(xy 46.99 132.08) (xy 81.28 132.08)
		)
		(stroke
			(width 0)
			(type default)
		)
	)
	(wire
		(pts
			(xy 63.5 119.38) (xy 63.5 123.19)
		)
		(stroke
			(width 0)
			(type default)
		)
	)
	(wire
		(pts
			(xy 81.28 109.22) (xy 80.01 109.22)
		)
		(stroke
			(width 0)
			(type default)
		)
	)
	(wire
		(pts
			(xy 220.98 151.13) (xy 220.98 152.4)
		)
		(stroke
			(width 0)
			(type default)
		)
	)
	(wire
		(pts
			(xy 80.01 50.8) (xy 80.01 53.34)
		)
		(stroke
			(width 0)
			(type default)
		)
	)
	(bus
		(pts
			(xy 64.77 78.74) (xy 64.77 81.28)
		)
		(stroke
			(width 0)
			(type default)
		)
	)
	(wire
		(pts
			(xy 106.68 229.87) (xy 125.73 229.87)
		)
		(stroke
			(width 0)
			(type default)
		)
	)
	(wire
		(pts
			(xy 368.3 135.89) (xy 353.06 135.89)
		)
		(stroke
			(width 0)
			(type default)
		)
	)
	(wire
		(pts
			(xy 182.88 242.57) (xy 182.88 243.84)
		)
		(stroke
			(width 0)
			(type default)
		)
	)
	(wire
		(pts
			(xy 382.27 53.34) (xy 384.81 53.34)
		)
		(stroke
			(width 0)
			(type default)
		)
	)
	(wire
		(pts
			(xy 322.58 50.8) (xy 322.58 53.34)
		)
		(stroke
			(width 0)
			(type default)
		)
	)
	(bus
		(pts
			(xy 73.66 228.6) (xy 73.66 231.14)
		)
		(stroke
			(width 0)
			(type default)
		)
	)
	(wire
		(pts
			(xy 353.06 119.38) (xy 353.06 125.73)
		)
		(stroke
			(width 0)
			(type default)
		)
	)
	(wire
		(pts
			(xy 63.5 234.95) (xy 63.5 231.14)
		)
		(stroke
			(width 0)
			(type default)
		)
	)
	(wire
		(pts
			(xy 213.36 115.57) (xy 220.98 115.57)
		)
		(stroke
			(width 0)
			(type default)
		)
	)
	(bus
		(pts
			(xy 64.77 81.28) (xy 64.77 83.82)
		)
		(stroke
			(width 0)
			(type default)
		)
	)
	(wire
		(pts
			(xy 229.87 124.46) (xy 229.87 128.27)
		)
		(stroke
			(width 0)
			(type default)
		)
	)
	(wire
		(pts
			(xy 213.36 124.46) (xy 213.36 130.81)
		)
		(stroke
			(width 0)
			(type default)
		)
	)
	(wire
		(pts
			(xy 187.96 128.27) (xy 229.87 128.27)
		)
		(stroke
			(width 0)
			(type default)
		)
	)
	(wire
		(pts
			(xy 220.98 124.46) (xy 220.98 133.35)
		)
		(stroke
			(width 0)
			(type default)
		)
	)
	(wire
		(pts
			(xy 336.55 45.72) (xy 347.98 45.72)
		)
		(stroke
			(width 0)
			(type default)
		)
	)
	(bus
		(pts
			(xy 64.77 83.82) (xy 64.77 86.36)
		)
		(stroke
			(width 0)
			(type default)
		)
	)
	(wire
		(pts
			(xy 353.06 138.43) (xy 353.06 135.89)
		)
		(stroke
			(width 0)
			(type default)
		)
	)
	(wire
		(pts
			(xy 220.98 138.43) (xy 220.98 139.7)
		)
		(stroke
			(width 0)
			(type default)
		)
	)
	(wire
		(pts
			(xy 54.61 237.49) (xy 88.9 237.49)
		)
		(stroke
			(width 0)
			(type default)
		)
	)
	(wire
		(pts
			(xy 226.06 48.26) (xy 231.14 48.26)
		)
		(stroke
			(width 0)
			(type default)
		)
	)
	(wire
		(pts
			(xy 46.99 134.62) (xy 81.28 134.62)
		)
		(stroke
			(width 0)
			(type default)
		)
	)
	(wire
		(pts
			(xy 243.84 59.69) (xy 243.84 52.07)
		)
		(stroke
			(width 0)
			(type default)
		)
	)
	(wire
		(pts
			(xy 267.97 214.63) (xy 267.97 217.17)
		)
		(stroke
			(width 0)
			(type default)
		)
	)
	(wire
		(pts
			(xy 346.71 209.55) (xy 346.71 208.28)
		)
		(stroke
			(width 0)
			(type default)
		)
	)
	(wire
		(pts
			(xy 77.47 116.84) (xy 81.28 116.84)
		)
		(stroke
			(width 0)
			(type default)
		)
	)
	(wire
		(pts
			(xy 74.93 229.87) (xy 88.9 229.87)
		)
		(stroke
			(width 0)
			(type default)
		)
	)
	(wire
		(pts
			(xy 195.58 46.99) (xy 195.58 48.26)
		)
		(stroke
			(width 0)
			(type default)
		)
	)
	(wire
		(pts
			(xy 267.97 222.25) (xy 267.97 223.52)
		)
		(stroke
			(width 0)
			(type default)
		)
	)
	(wire
		(pts
			(xy 208.28 133.35) (xy 208.28 140.97)
		)
		(stroke
			(width 0)
			(type default)
		)
	)
	(wire
		(pts
			(xy 69.85 113.03) (xy 77.47 113.03)
		)
		(stroke
			(width 0)
			(type default)
		)
	)
	(wire
		(pts
			(xy 87.63 224.79) (xy 88.9 224.79)
		)
		(stroke
			(width 0)
			(type default)
		)
	)
	(wire
		(pts
			(xy 326.39 50.8) (xy 322.58 50.8)
		)
		(stroke
			(width 0)
			(type default)
		)
	)
	(wire
		(pts
			(xy 334.01 119.38) (xy 334.01 125.73)
		)
		(stroke
			(width 0)
			(type default)
		)
	)
	(wire
		(pts
			(xy 322.58 45.72) (xy 322.58 48.26)
		)
		(stroke
			(width 0)
			(type default)
		)
	)
	(bus
		(pts
			(xy 73.66 213.36) (xy 73.66 228.6)
		)
		(stroke
			(width 0)
			(type default)
		)
	)
	(wire
		(pts
			(xy 243.84 52.07) (xy 245.11 52.07)
		)
		(stroke
			(width 0)
			(type default)
		)
	)
	(wire
		(pts
			(xy 67.31 83.82) (xy 81.28 83.82)
		)
		(stroke
			(width 0)
			(type default)
		)
	)
	(wire
		(pts
			(xy 336.55 48.26) (xy 347.98 48.26)
		)
		(stroke
			(width 0)
			(type default)
		)
	)
	(wire
		(pts
			(xy 68.58 58.42) (xy 81.28 58.42)
		)
		(stroke
			(width 0)
			(type default)
		)
	)
	(wire
		(pts
			(xy 63.5 123.19) (xy 69.85 123.19)
		)
		(stroke
			(width 0)
			(type default)
		)
	)
	(wire
		(pts
			(xy 173.99 238.76) (xy 175.26 238.76)
		)
		(stroke
			(width 0)
			(type default)
		)
	)
	(wire
		(pts
			(xy 220.98 133.35) (xy 208.28 133.35)
		)
		(stroke
			(width 0)
			(type default)
		)
	)
	(bus
		(pts
			(xy 60.96 77.47) (xy 63.5 77.47)
		)
		(stroke
			(width 0)
			(type default)
		)
	)
	(wire
		(pts
			(xy 336.55 43.18) (xy 347.98 43.18)
		)
		(stroke
			(width 0)
			(type default)
		)
	)
	(wire
		(pts
			(xy 80.01 111.76) (xy 80.01 139.7)
		)
		(stroke
			(width 0)
			(type default)
		)
	)
	(bus
		(pts
			(xy 45.72 62.23) (xy 45.72 64.77)
		)
		(stroke
			(width 0)
			(type default)
		)
	)
	(wire
		(pts
			(xy 337.82 217.17) (xy 337.82 220.98)
		)
		(stroke
			(width 0)
			(type default)
		)
	)
	(wire
		(pts
			(xy 46.99 116.84) (xy 63.5 116.84)
		)
		(stroke
			(width 0)
			(type default)
		)
	)
	(wire
		(pts
			(xy 46.99 99.06) (xy 81.28 99.06)
		)
		(stroke
			(width 0)
			(type default)
		)
	)
	(wire
		(pts
			(xy 231.14 48.26) (xy 231.14 52.07)
		)
		(stroke
			(width 0)
			(type default)
		)
	)
	(wire
		(pts
			(xy 68.58 73.66) (xy 81.28 73.66)
		)
		(stroke
			(width 0)
			(type default)
		)
	)
	(wire
		(pts
			(xy 231.14 59.69) (xy 231.14 60.96)
		)
		(stroke
			(width 0)
			(type default)
		)
	)
	(wire
		(pts
			(xy 187.96 130.81) (xy 213.36 130.81)
		)
		(stroke
			(width 0)
			(type default)
		)
	)
	(wire
		(pts
			(xy 68.58 60.96) (xy 81.28 60.96)
		)
		(stroke
			(width 0)
			(type default)
		)
	)
	(label "JTAG.TDI"
		(at 347.98 50.8 180)
		(effects
			(font
				(size 1.27 1.27)
			)
			(justify right bottom)
		)
	)
	(label "MODE0"
		(at 327.66 220.98 0)
		(effects
			(font
				(size 1.27 1.27)
			)
			(justify left bottom)
		)
	)
	(label "MODE0"
		(at 68.58 73.66 0)
		(effects
			(font
				(size 1.27 1.27)
			)
			(justify left bottom)
		)
	)
	(label "~{THERM}"
		(at 46.99 237.49 0)
		(effects
			(font
				(size 1.27 1.27)
			)
			(justify left bottom)
		)
	)
	(label "DONE"
		(at 187.96 128.27 0)
		(effects
			(font
				(size 1.27 1.27)
			)
			(justify left bottom)
		)
	)
	(label "FLASH.IO2"
		(at 46.99 101.6 0)
		(effects
			(font
				(size 1.27 1.27)
			)
			(justify left bottom)
		)
	)
	(label "INIT_B"
		(at 68.58 60.96 0)
		(effects
			(font
				(size 1.27 1.27)
			)
			(justify left bottom)
		)
	)
	(label "PROGRAM_B"
		(at 187.96 133.35 0)
		(effects
			(font
				(size 1.27 1.27)
			)
			(justify left bottom)
		)
	)
	(label "JTAG.TDO"
		(at 391.16 48.26 180)
		(effects
			(font
				(size 1.27 1.27)
			)
			(justify right bottom)
		)
	)
	(label "POR_OVERRIDE"
		(at 368.3 135.89 180)
		(effects
			(font
				(size 1.27 1.27)
			)
			(justify right bottom)
		)
	)
	(label "INIT_B"
		(at 209.55 238.76 0)
		(effects
			(font
				(size 1.27 1.27)
			)
			(justify left bottom)
		)
	)
	(label "MODE1"
		(at 334.01 223.52 180)
		(effects
			(font
				(size 1.27 1.27)
			)
			(justify right bottom)
		)
	)
	(label "PUDC_B"
		(at 345.44 135.89 180)
		(effects
			(font
				(size 1.27 1.27)
			)
			(justify right bottom)
		)
	)
	(label "JTAG.TCK"
		(at 347.98 45.72 180)
		(effects
			(font
				(size 1.27 1.27)
			)
			(justify right bottom)
		)
	)
	(label "DONE"
		(at 68.58 58.42 0)
		(effects
			(font
				(size 1.27 1.27)
			)
			(justify left bottom)
		)
	)
	(label "JTAG.TCK"
		(at 76.2 83.82 180)
		(effects
			(font
				(size 1.27 1.27)
			)
			(justify right bottom)
		)
	)
	(label "FLASH.IO1"
		(at 46.99 99.06 0)
		(effects
			(font
				(size 1.27 1.27)
			)
			(justify left bottom)
		)
	)
	(label "MODE2"
		(at 68.58 78.74 0)
		(effects
			(font
				(size 1.27 1.27)
			)
			(justify left bottom)
		)
	)
	(label "JTAG.TCK"
		(at 391.16 45.72 180)
		(effects
			(font
				(size 1.27 1.27)
			)
			(justify right bottom)
		)
	)
	(label "VREFP"
		(at 46.99 116.84 0)
		(effects
			(font
				(size 1.27 1.27)
			)
			(justify left bottom)
		)
	)
	(label "DX_P"
		(at 125.73 227.33 180)
		(effects
			(font
				(size 1.27 1.27)
			)
			(justify right bottom)
		)
	)
	(label "VREFN"
		(at 259.08 52.07 180)
		(effects
			(font
				(size 1.27 1.27)
			)
			(justify right bottom)
		)
	)
	(label "JTAG.TDO"
		(at 76.2 88.9 180)
		(effects
			(font
				(size 1.27 1.27)
			)
			(justify right bottom)
		)
	)
	(label "POR_OVERRIDE"
		(at 46.99 132.08 0)
		(effects
			(font
				(size 1.27 1.27)
			)
			(justify left bottom)
		)
	)
	(label "FPGA_PWR.SCL"
		(at 74.93 232.41 0)
		(effects
			(font
				(size 1.27 1.27)
			)
			(justify left bottom)
		)
	)
	(label "JTAG.TMS"
		(at 347.98 43.18 180)
		(effects
			(font
				(size 1.27 1.27)
			)
			(justify right bottom)
		)
	)
	(label "DX_N"
		(at 46.99 127 0)
		(effects
			(font
				(size 1.27 1.27)
			)
			(justify left bottom)
		)
	)
	(label "JTAG.TMS"
		(at 76.2 91.44 180)
		(effects
			(font
				(size 1.27 1.27)
			)
			(justify right bottom)
		)
	)
	(label "MODE1"
		(at 68.58 76.2 0)
		(effects
			(font
				(size 1.27 1.27)
			)
			(justify left bottom)
		)
	)
	(label "FPGA_PWR.SDA"
		(at 74.93 229.87 0)
		(effects
			(font
				(size 1.27 1.27)
			)
			(justify left bottom)
		)
	)
	(label "DX_N"
		(at 125.73 229.87 180)
		(effects
			(font
				(size 1.27 1.27)
			)
			(justify right bottom)
		)
	)
	(label "VREFP"
		(at 259.08 48.26 180)
		(effects
			(font
				(size 1.27 1.27)
			)
			(justify right bottom)
		)
	)
	(label "VREFN"
		(at 46.99 119.38 0)
		(effects
			(font
				(size 1.27 1.27)
			)
			(justify left bottom)
		)
	)
	(label "INIT_B"
		(at 187.96 130.81 0)
		(effects
			(font
				(size 1.27 1.27)
			)
			(justify left bottom)
		)
	)
	(label "FLASH.SCK"
		(at 46.99 71.12 0)
		(effects
			(font
				(size 1.27 1.27)
			)
			(justify left bottom)
		)
	)
	(label "JTAG.TDI"
		(at 76.2 86.36 180)
		(effects
			(font
				(size 1.27 1.27)
			)
			(justify right bottom)
		)
	)
	(label "PUDC_B"
		(at 46.99 134.62 0)
		(effects
			(font
				(size 1.27 1.27)
			)
			(justify left bottom)
		)
	)
	(label "DX_P"
		(at 46.99 124.46 0)
		(effects
			(font
				(size 1.27 1.27)
			)
			(justify left bottom)
		)
	)
	(label "DONE"
		(at 255.27 238.76 0)
		(effects
			(font
				(size 1.27 1.27)
			)
			(justify left bottom)
		)
	)
	(label "~{ALARM}"
		(at 46.99 234.95 0)
		(effects
			(font
				(size 1.27 1.27)
			)
			(justify left bottom)
		)
	)
	(label "FLASH.IO3"
		(at 46.99 104.14 0)
		(effects
			(font
				(size 1.27 1.27)
			)
			(justify left bottom)
		)
	)
	(label "FLASH.IO0"
		(at 46.99 96.52 0)
		(effects
			(font
				(size 1.27 1.27)
			)
			(justify left bottom)
		)
	)
	(label "JTAG.TDO"
		(at 347.98 48.26 180)
		(effects
			(font
				(size 1.27 1.27)
			)
			(justify right bottom)
		)
	)
	(label "JTAG.TDI"
		(at 391.16 50.8 180)
		(effects
			(font
				(size 1.27 1.27)
			)
			(justify right bottom)
		)
	)
	(label "JTAG.TMS"
		(at 391.16 43.18 180)
		(effects
			(font
				(size 1.27 1.27)
			)
			(justify right bottom)
		)
	)
	(label "PROGRAM_B"
		(at 68.58 63.5 0)
		(effects
			(font
				(size 1.27 1.27)
			)
			(justify left bottom)
		)
	)
	(label "FLASH.~{CS}"
		(at 46.99 66.04 0)
		(effects
			(font
				(size 1.27 1.27)
			)
			(justify left bottom)
		)
	)
	(global_label "MODE2"
		(shape input)
		(at 335.28 226.06 180)
		(fields_autoplaced yes)
		(effects
			(font
				(size 1.27 1.27)
			)
			(justify right)
		)
		(property "Intersheetrefs" "${INTERSHEET_REFS}"
			(at 326.5386 226.06 0)
			(effects
				(font
					(size 1.27 1.27)
				)
				(justify right)
			)
		)
	)
	(global_label "POWER"
		(shape input)
		(at 173.99 238.76 180)
		(fields_autoplaced yes)
		(effects
			(font
				(size 1.27 1.27)
			)
			(justify right)
		)
		(property "Intersheetrefs" "${INTERSHEET_REFS}"
			(at 165.1948 238.8394 0)
			(effects
				(font
					(size 1.27 1.27)
				)
				(justify right)
			)
		)
	)
	(hierarchical_label "FPGA_PWR{I^{2}C}"
		(shape bidirectional)
		(at 71.12 213.36 180)
		(effects
			(font
				(size 1.27 1.27)
			)
			(justify right)
		)
	)
	(hierarchical_label "JTAG{JTAG}"
		(shape bidirectional)
		(at 60.96 77.47 180)
		(effects
			(font
				(size 1.27 1.27)
			)
			(justify right)
		)
	)
	(hierarchical_label "FLASH{QSPI}"
		(shape bidirectional)
		(at 41.91 60.96 180)
		(effects
			(font
				(size 1.27 1.27)
			)
			(justify right)
		)
	)
	(symbol
		(lib_id "antmicropower:GND")
		(at 322.58 60.96 0)
		(unit 1)
		(exclude_from_sim no)
		(in_bom yes)
		(on_board yes)
		(dnp no)
		(fields_autoplaced yes)
		(property "Reference" "#PWR0182"
			(at 322.58 67.31 0)
			(effects
				(font
					(size 1.27 1.27)
				)
				(hide yes)
			)
		)
		(property "Value" "GND"
			(at 320.675 65.405 0)
			(effects
				(font
					(size 1.27 1.27)
					(thickness 0.15)
				)
				(justify left bottom)
			)
		)
		(property "Footprint" ""
			(at 331.47 68.58 0)
			(effects
				(font
					(size 1.27 1.27)
					(thickness 0.15)
				)
				(justify left bottom)
				(hide yes)
			)
		)
		(property "Datasheet" ""
			(at 331.47 73.66 0)
			(effects
				(font
					(size 1.27 1.27)
					(thickness 0.15)
				)
				(justify left bottom)
				(hide yes)
			)
		)
		(property "Description" ""
			(at 322.58 60.96 0)
			(effects
				(font
					(size 1.27 1.27)
				)
				(hide yes)
			)
		)
		(property "Author" "Antmicro"
			(at 331.47 66.04 0)
			(effects
				(font
					(size 1.27 1.27)
					(thickness 0.15)
				)
				(justify left bottom)
				(hide yes)
			)
		)
		(property "License" "Apache-2.0"
			(at 331.47 68.58 0)
			(effects
				(font
					(size 1.27 1.27)
					(thickness 0.15)
				)
				(justify left bottom)
				(hide yes)
			)
		)
		(pin "1"
		)
		(instances
			(project "data-center-rdimm-ddr5-tester"
				(path ""
					(reference "#PWR0182")
					(unit 1)
				)
			)
		)
	)
	(symbol
		(lib_id "antmicropower:GND")
		(at 384.81 58.42 0)
		(unit 1)
		(exclude_from_sim no)
		(in_bom yes)
		(on_board yes)
		(dnp no)
		(fields_autoplaced yes)
		(property "Reference" "#PWR0183"
			(at 384.81 64.77 0)
			(effects
				(font
					(size 1.27 1.27)
				)
				(hide yes)
			)
		)
		(property "Value" "GND"
			(at 382.905 62.865 0)
			(effects
				(font
					(size 1.27 1.27)
					(thickness 0.15)
				)
				(justify left bottom)
			)
		)
		(property "Footprint" ""
			(at 393.7 66.04 0)
			(effects
				(font
					(size 1.27 1.27)
					(thickness 0.15)
				)
				(justify left bottom)
				(hide yes)
			)
		)
		(property "Datasheet" ""
			(at 393.7 71.12 0)
			(effects
				(font
					(size 1.27 1.27)
					(thickness 0.15)
				)
				(justify left bottom)
				(hide yes)
			)
		)
		(property "Description" ""
			(at 384.81 58.42 0)
			(effects
				(font
					(size 1.27 1.27)
				)
				(hide yes)
			)
		)
		(property "Author" "Antmicro"
			(at 393.7 63.5 0)
			(effects
				(font
					(size 1.27 1.27)
					(thickness 0.15)
				)
				(justify left bottom)
				(hide yes)
			)
		)
		(property "License" "Apache-2.0"
			(at 393.7 66.04 0)
			(effects
				(font
					(size 1.27 1.27)
					(thickness 0.15)
				)
				(justify left bottom)
				(hide yes)
			)
		)
		(pin "1"
		)
		(instances
			(project "data-center-rdimm-ddr5-tester"
				(path ""
					(reference "#PWR0183")
					(unit 1)
				)
			)
		)
	)
	(symbol
		(lib_id "antmicroResistors0402:R_4k7_0402")
		(at 220.98 119.38 270)
		(unit 1)
		(exclude_from_sim no)
		(in_bom yes)
		(on_board yes)
		(dnp no)
		(property "Reference" "R18"
			(at 221.615 118.745 90)
			(effects
				(font
					(size 1.27 1.27)
				)
				(justify left)
			)
		)
		(property "Value" "R_4k7_0402"
			(at 208.28 139.7 0)
			(effects
				(font
					(size 1.27 1.27)
					(thickness 0.15)
				)
				(justify left bottom)
				(hide yes)
			)
		)
		(property "Footprint" "antmicro-footprints:R_0402_1005Metric_EIA"
			(at 205.74 139.7 0)
			(effects
				(font
					(size 1.27 1.27)
					(thickness 0.15)
				)
				(justify left bottom)
				(hide yes)
			)
		)
		(property "Datasheet" "https://www.bourns.com/docs/product-datasheets/cr.pdf"
			(at 203.2 139.7 0)
			(effects
				(font
					(size 1.27 1.27)
					(thickness 0.15)
				)
				(justify left bottom)
				(hide yes)
			)
		)
		(property "Description" ""
			(at 220.98 119.38 0)
			(effects
				(font
					(size 1.27 1.27)
				)
				(hide yes)
			)
		)
		(property "Manufacturer" "Bourns"
			(at 198.12 139.7 0)
			(effects
				(font
					(size 1.27 1.27)
					(thickness 0.15)
				)
				(justify left bottom)
				(hide yes)
			)
		)
		(property "MPN" "CR0402-FX-4701GLF"
			(at 200.66 139.7 0)
			(effects
				(font
					(size 1.27 1.27)
					(thickness 0.15)
				)
				(justify left bottom)
				(hide yes)
			)
		)
		(property "Val" "4k7"
			(at 222.885 123.8249 90)
			(effects
				(font
					(size 1.27 1.27)
					(thickness 0.15)
				)
				(justify left)
			)
		)
		(property "License" "Apache-2.0"
			(at 195.58 139.7 0)
			(effects
				(font
					(size 1.27 1.27)
					(thickness 0.15)
				)
				(justify left bottom)
				(hide yes)
			)
		)
		(property "Author" "Antmicro"
			(at 193.04 139.7 0)
			(effects
				(font
					(size 1.27 1.27)
					(thickness 0.15)
				)
				(justify left bottom)
				(hide yes)
			)
		)
		(property "Tolerance" "1%"
			(at 210.82 139.7 0)
			(effects
				(font
					(size 1.27 1.27)
				)
				(justify left bottom)
				(hide yes)
			)
		)
		(pin "1"
		)
		(pin "2"
		)
		(instances
			(project "data-center-rdimm-ddr5-tester"
				(path ""
					(reference "R18")
					(unit 1)
				)
			)
		)
	)
	(symbol
		(lib_id "antmicroResistors0402:R_330R_0402")
		(at 229.87 119.38 270)
		(unit 1)
		(exclude_from_sim no)
		(in_bom yes)
		(on_board yes)
		(dnp no)
		(property "Reference" "R19"
			(at 230.505 118.745 90)
			(effects
				(font
					(size 1.27 1.27)
				)
				(justify left)
			)
		)
		(property "Value" "R_330R_0402"
			(at 217.17 139.7 0)
			(effects
				(font
					(size 1.27 1.27)
					(thickness 0.15)
				)
				(justify left bottom)
				(hide yes)
			)
		)
		(property "Footprint" "antmicro-footprints:R_0402_1005Metric"
			(at 214.63 139.7 0)
			(effects
				(font
					(size 1.27 1.27)
					(thickness 0.15)
				)
				(justify left bottom)
				(hide yes)
			)
		)
		(property "Datasheet" "https://www.bourns.com/docs/product-datasheets/cr.pdf"
			(at 212.09 139.7 0)
			(effects
				(font
					(size 1.27 1.27)
					(thickness 0.15)
				)
				(justify left bottom)
				(hide yes)
			)
		)
		(property "Description" ""
			(at 229.87 119.38 0)
			(effects
				(font
					(size 1.27 1.27)
				)
				(hide yes)
			)
		)
		(property "Manufacturer" "Bourns"
			(at 207.01 139.7 0)
			(effects
				(font
					(size 1.27 1.27)
					(thickness 0.15)
				)
				(justify left bottom)
				(hide yes)
			)
		)
		(property "MPN" "CR0402-FX-3300GLF"
			(at 209.55 139.7 0)
			(effects
				(font
					(size 1.27 1.27)
					(thickness 0.15)
				)
				(justify left bottom)
				(hide yes)
			)
		)
		(property "Val" "330R"
			(at 231.775 123.8249 90)
			(effects
				(font
					(size 1.27 1.27)
					(thickness 0.15)
				)
				(justify left)
			)
		)
		(property "License" "Apache-2.0"
			(at 204.47 139.7 0)
			(effects
				(font
					(size 1.27 1.27)
					(thickness 0.15)
				)
				(justify left bottom)
				(hide yes)
			)
		)
		(property "Author" "Antmicro"
			(at 201.93 139.7 0)
			(effects
				(font
					(size 1.27 1.27)
					(thickness 0.15)
				)
				(justify left bottom)
				(hide yes)
			)
		)
		(property "Tolerance" "1%"
			(at 219.71 139.7 0)
			(effects
				(font
					(size 1.27 1.27)
				)
				(justify left bottom)
				(hide yes)
			)
		)
		(pin "1"
		)
		(pin "2"
		)
		(instances
			(project "data-center-rdimm-ddr5-tester"
				(path ""
					(reference "R19")
					(unit 1)
				)
			)
		)
	)
	(symbol
		(lib_id "antmicropower:GND")
		(at 267.97 243.84 0)
		(unit 1)
		(exclude_from_sim no)
		(in_bom yes)
		(on_board yes)
		(dnp no)
		(fields_autoplaced yes)
		(property "Reference" "#PWR0186"
			(at 267.97 250.19 0)
			(effects
				(font
					(size 1.27 1.27)
				)
				(hide yes)
			)
		)
		(property "Value" "GND"
			(at 266.065 248.285 0)
			(effects
				(font
					(size 1.27 1.27)
					(thickness 0.15)
				)
				(justify left bottom)
			)
		)
		(property "Footprint" ""
			(at 276.86 251.46 0)
			(effects
				(font
					(size 1.27 1.27)
					(thickness 0.15)
				)
				(justify left bottom)
				(hide yes)
			)
		)
		(property "Datasheet" ""
			(at 276.86 256.54 0)
			(effects
				(font
					(size 1.27 1.27)
					(thickness 0.15)
				)
				(justify left bottom)
				(hide yes)
			)
		)
		(property "Description" ""
			(at 267.97 243.84 0)
			(effects
				(font
					(size 1.27 1.27)
				)
				(hide yes)
			)
		)
		(property "Author" "Antmicro"
			(at 276.86 248.92 0)
			(effects
				(font
					(size 1.27 1.27)
					(thickness 0.15)
				)
				(justify left bottom)
				(hide yes)
			)
		)
		(property "License" "Apache-2.0"
			(at 276.86 251.46 0)
			(effects
				(font
					(size 1.27 1.27)
					(thickness 0.15)
				)
				(justify left bottom)
				(hide yes)
			)
		)
		(pin "1"
		)
		(instances
			(project "data-center-rdimm-ddr5-tester"
				(path ""
					(reference "#PWR0186")
					(unit 1)
				)
			)
		)
	)
	(symbol
		(lib_id "antmicroResistors0402:R_330R_0402")
		(at 267.97 223.52 270)
		(unit 1)
		(exclude_from_sim no)
		(in_bom yes)
		(on_board yes)
		(dnp no)
		(fields_autoplaced yes)
		(property "Reference" "R12"
			(at 269.621 225.2294 90)
			(effects
				(font
					(size 1.27 1.27)
				)
				(justify left)
			)
		)
		(property "Value" "R_330R_0402"
			(at 255.27 243.84 0)
			(effects
				(font
					(size 1.27 1.27)
					(thickness 0.15)
				)
				(justify left bottom)
				(hide yes)
			)
		)
		(property "Footprint" "antmicro-footprints:R_0402_1005Metric"
			(at 252.73 243.84 0)
			(effects
				(font
					(size 1.27 1.27)
					(thickness 0.15)
				)
				(justify left bottom)
				(hide yes)
			)
		)
		(property "Datasheet" "https://www.bourns.com/docs/product-datasheets/cr.pdf"
			(at 250.19 243.84 0)
			(effects
				(font
					(size 1.27 1.27)
					(thickness 0.15)
				)
				(justify left bottom)
				(hide yes)
			)
		)
		(property "Description" ""
			(at 267.97 223.52 0)
			(effects
				(font
					(size 1.27 1.27)
				)
				(hide yes)
			)
		)
		(property "Manufacturer" "Bourns"
			(at 245.11 243.84 0)
			(effects
				(font
					(size 1.27 1.27)
					(thickness 0.15)
				)
				(justify left bottom)
				(hide yes)
			)
		)
		(property "MPN" "CR0402-FX-3300GLF"
			(at 247.65 243.84 0)
			(effects
				(font
					(size 1.27 1.27)
					(thickness 0.15)
				)
				(justify left bottom)
				(hide yes)
			)
		)
		(property "Val" "330R"
			(at 269.621 227.7597 90)
			(effects
				(font
					(size 1.27 1.27)
					(thickness 0.15)
				)
				(justify left)
			)
		)
		(property "License" "Apache-2.0"
			(at 242.57 243.84 0)
			(effects
				(font
					(size 1.27 1.27)
					(thickness 0.15)
				)
				(justify left bottom)
				(hide yes)
			)
		)
		(property "Author" "Antmicro"
			(at 240.03 243.84 0)
			(effects
				(font
					(size 1.27 1.27)
					(thickness 0.15)
				)
				(justify left bottom)
				(hide yes)
			)
		)
		(property "Tolerance" "1%"
			(at 257.81 243.84 0)
			(effects
				(font
					(size 1.27 1.27)
				)
				(justify left bottom)
				(hide yes)
			)
		)
		(pin "1"
		)
		(pin "2"
		)
		(instances
			(project "data-center-rdimm-ddr5-tester"
				(path ""
					(reference "R12")
					(unit 1)
				)
			)
		)
	)
	(symbol
		(lib_id "antmicropower:GND")
		(at 224.79 243.84 0)
		(unit 1)
		(exclude_from_sim no)
		(in_bom yes)
		(on_board yes)
		(dnp no)
		(fields_autoplaced yes)
		(property "Reference" "#PWR0174"
			(at 224.79 250.19 0)
			(effects
				(font
					(size 1.27 1.27)
				)
				(hide yes)
			)
		)
		(property "Value" "GND"
			(at 222.885 248.285 0)
			(effects
				(font
					(size 1.27 1.27)
					(thickness 0.15)
				)
				(justify left bottom)
			)
		)
		(property "Footprint" ""
			(at 233.68 251.46 0)
			(effects
				(font
					(size 1.27 1.27)
					(thickness 0.15)
				)
				(justify left bottom)
				(hide yes)
			)
		)
		(property "Datasheet" ""
			(at 233.68 256.54 0)
			(effects
				(font
					(size 1.27 1.27)
					(thickness 0.15)
				)
				(justify left bottom)
				(hide yes)
			)
		)
		(property "Description" ""
			(at 224.79 243.84 0)
			(effects
				(font
					(size 1.27 1.27)
				)
				(hide yes)
			)
		)
		(property "Author" "Antmicro"
			(at 233.68 248.92 0)
			(effects
				(font
					(size 1.27 1.27)
					(thickness 0.15)
				)
				(justify left bottom)
				(hide yes)
			)
		)
		(property "License" "Apache-2.0"
			(at 233.68 251.46 0)
			(effects
				(font
					(size 1.27 1.27)
					(thickness 0.15)
				)
				(justify left bottom)
				(hide yes)
			)
		)
		(pin "1"
		)
		(instances
			(project "data-center-rdimm-ddr5-tester"
				(path ""
					(reference "#PWR0174")
					(unit 1)
				)
			)
		)
	)
	(symbol
		(lib_id "antmicroResistors0402:R_330R_0402")
		(at 224.79 223.52 270)
		(unit 1)
		(exclude_from_sim no)
		(in_bom yes)
		(on_board yes)
		(dnp no)
		(fields_autoplaced yes)
		(property "Reference" "R13"
			(at 226.441 225.2294 90)
			(effects
				(font
					(size 1.27 1.27)
				)
				(justify left)
			)
		)
		(property "Value" "R_330R_0402"
			(at 212.09 243.84 0)
			(effects
				(font
					(size 1.27 1.27)
					(thickness 0.15)
				)
				(justify left bottom)
				(hide yes)
			)
		)
		(property "Footprint" "antmicro-footprints:R_0402_1005Metric"
			(at 209.55 243.84 0)
			(effects
				(font
					(size 1.27 1.27)
					(thickness 0.15)
				)
				(justify left bottom)
				(hide yes)
			)
		)
		(property "Datasheet" "https://www.bourns.com/docs/product-datasheets/cr.pdf"
			(at 207.01 243.84 0)
			(effects
				(font
					(size 1.27 1.27)
					(thickness 0.15)
				)
				(justify left bottom)
				(hide yes)
			)
		)
		(property "Description" ""
			(at 224.79 223.52 0)
			(effects
				(font
					(size 1.27 1.27)
				)
				(hide yes)
			)
		)
		(property "Manufacturer" "Bourns"
			(at 201.93 243.84 0)
			(effects
				(font
					(size 1.27 1.27)
					(thickness 0.15)
				)
				(justify left bottom)
				(hide yes)
			)
		)
		(property "MPN" "CR0402-FX-3300GLF"
			(at 204.47 243.84 0)
			(effects
				(font
					(size 1.27 1.27)
					(thickness 0.15)
				)
				(justify left bottom)
				(hide yes)
			)
		)
		(property "Val" "330R"
			(at 226.441 227.7597 90)
			(effects
				(font
					(size 1.27 1.27)
					(thickness 0.15)
				)
				(justify left)
			)
		)
		(property "License" "Apache-2.0"
			(at 199.39 243.84 0)
			(effects
				(font
					(size 1.27 1.27)
					(thickness 0.15)
				)
				(justify left bottom)
				(hide yes)
			)
		)
		(property "Author" "Antmicro"
			(at 196.85 243.84 0)
			(effects
				(font
					(size 1.27 1.27)
					(thickness 0.15)
				)
				(justify left bottom)
				(hide yes)
			)
		)
		(property "Tolerance" "1%"
			(at 214.63 243.84 0)
			(effects
				(font
					(size 1.27 1.27)
				)
				(justify left bottom)
				(hide yes)
			)
		)
		(pin "1"
		)
		(pin "2"
		)
		(instances
			(project "data-center-rdimm-ddr5-tester"
				(path ""
					(reference "R13")
					(unit 1)
				)
			)
		)
	)
	(symbol
		(lib_id "antmicropower:GND")
		(at 220.98 152.4 0)
		(unit 1)
		(exclude_from_sim no)
		(in_bom yes)
		(on_board yes)
		(dnp no)
		(fields_autoplaced yes)
		(property "Reference" "#PWR0187"
			(at 220.98 158.75 0)
			(effects
				(font
					(size 1.27 1.27)
				)
				(hide yes)
			)
		)
		(property "Value" "GND"
			(at 219.075 156.845 0)
			(effects
				(font
					(size 1.27 1.27)
					(thickness 0.15)
				)
				(justify left bottom)
			)
		)
		(property "Footprint" ""
			(at 229.87 160.02 0)
			(effects
				(font
					(size 1.27 1.27)
					(thickness 0.15)
				)
				(justify left bottom)
				(hide yes)
			)
		)
		(property "Datasheet" ""
			(at 229.87 165.1 0)
			(effects
				(font
					(size 1.27 1.27)
					(thickness 0.15)
				)
				(justify left bottom)
				(hide yes)
			)
		)
		(property "Description" ""
			(at 220.98 152.4 0)
			(effects
				(font
					(size 1.27 1.27)
				)
				(hide yes)
			)
		)
		(property "Author" "Antmicro"
			(at 229.87 157.48 0)
			(effects
				(font
					(size 1.27 1.27)
					(thickness 0.15)
				)
				(justify left bottom)
				(hide yes)
			)
		)
		(property "License" "Apache-2.0"
			(at 229.87 160.02 0)
			(effects
				(font
					(size 1.27 1.27)
					(thickness 0.15)
				)
				(justify left bottom)
				(hide yes)
			)
		)
		(pin "1"
		)
		(instances
			(project "data-center-rdimm-ddr5-tester"
				(path ""
					(reference "#PWR0187")
					(unit 1)
				)
			)
		)
	)
	(symbol
		(lib_id "antmicroResistors0402:R_4k7_0402")
		(at 213.36 119.38 270)
		(unit 1)
		(exclude_from_sim no)
		(in_bom yes)
		(on_board yes)
		(dnp no)
		(property "Reference" "R16"
			(at 213.995 118.7451 90)
			(effects
				(font
					(size 1.27 1.27)
				)
				(justify left)
			)
		)
		(property "Value" "R_4k7_0402"
			(at 200.66 139.7 0)
			(effects
				(font
					(size 1.27 1.27)
					(thickness 0.15)
				)
				(justify left bottom)
				(hide yes)
			)
		)
		(property "Footprint" "antmicro-footprints:R_0402_1005Metric"
			(at 198.12 139.7 0)
			(effects
				(font
					(size 1.27 1.27)
					(thickness 0.15)
				)
				(justify left bottom)
				(hide yes)
			)
		)
		(property "Datasheet" "https://www.bourns.com/docs/product-datasheets/cr.pdf"
			(at 195.58 139.7 0)
			(effects
				(font
					(size 1.27 1.27)
					(thickness 0.15)
				)
				(justify left bottom)
				(hide yes)
			)
		)
		(property "Description" ""
			(at 213.36 119.38 0)
			(effects
				(font
					(size 1.27 1.27)
				)
				(hide yes)
			)
		)
		(property "Manufacturer" "Bourns"
			(at 190.5 139.7 0)
			(effects
				(font
					(size 1.27 1.27)
					(thickness 0.15)
				)
				(justify left bottom)
				(hide yes)
			)
		)
		(property "MPN" "CR0402-FX-4701GLF"
			(at 193.04 139.7 0)
			(effects
				(font
					(size 1.27 1.27)
					(thickness 0.15)
				)
				(justify left bottom)
				(hide yes)
			)
		)
		(property "Val" "4k7"
			(at 215.265 123.825 90)
			(effects
				(font
					(size 1.27 1.27)
					(thickness 0.15)
				)
				(justify left)
			)
		)
		(property "License" "Apache-2.0"
			(at 187.96 139.7 0)
			(effects
				(font
					(size 1.27 1.27)
					(thickness 0.15)
				)
				(justify left bottom)
				(hide yes)
			)
		)
		(property "Author" "Antmicro"
			(at 185.42 139.7 0)
			(effects
				(font
					(size 1.27 1.27)
					(thickness 0.15)
				)
				(justify left bottom)
				(hide yes)
			)
		)
		(property "Tolerance" "1%"
			(at 203.2 139.7 0)
			(effects
				(font
					(size 1.27 1.27)
				)
				(justify left bottom)
				(hide yes)
			)
		)
		(pin "1"
		)
		(pin "2"
		)
		(instances
			(project "data-center-rdimm-ddr5-tester"
				(path ""
					(reference "R16")
					(unit 1)
				)
			)
		)
	)
	(symbol
		(lib_id "antmicroResistors0402:R_330R_0402")
		(at 182.88 223.52 270)
		(unit 1)
		(exclude_from_sim no)
		(in_bom yes)
		(on_board yes)
		(dnp no)
		(fields_autoplaced yes)
		(property "Reference" "R11"
			(at 184.531 225.2294 90)
			(effects
				(font
					(size 1.27 1.27)
				)
				(justify left)
			)
		)
		(property "Value" "R_330R_0402"
			(at 170.18 243.84 0)
			(effects
				(font
					(size 1.27 1.27)
					(thickness 0.15)
				)
				(justify left bottom)
				(hide yes)
			)
		)
		(property "Footprint" "antmicro-footprints:R_0402_1005Metric"
			(at 167.64 243.84 0)
			(effects
				(font
					(size 1.27 1.27)
					(thickness 0.15)
				)
				(justify left bottom)
				(hide yes)
			)
		)
		(property "Datasheet" "https://www.bourns.com/docs/product-datasheets/cr.pdf"
			(at 165.1 243.84 0)
			(effects
				(font
					(size 1.27 1.27)
					(thickness 0.15)
				)
				(justify left bottom)
				(hide yes)
			)
		)
		(property "Description" ""
			(at 182.88 223.52 0)
			(effects
				(font
					(size 1.27 1.27)
				)
				(hide yes)
			)
		)
		(property "Manufacturer" "Bourns"
			(at 160.02 243.84 0)
			(effects
				(font
					(size 1.27 1.27)
					(thickness 0.15)
				)
				(justify left bottom)
				(hide yes)
			)
		)
		(property "MPN" "CR0402-FX-3300GLF"
			(at 162.56 243.84 0)
			(effects
				(font
					(size 1.27 1.27)
					(thickness 0.15)
				)
				(justify left bottom)
				(hide yes)
			)
		)
		(property "Val" "330R"
			(at 184.531 227.7597 90)
			(effects
				(font
					(size 1.27 1.27)
					(thickness 0.15)
				)
				(justify left)
			)
		)
		(property "License" "Apache-2.0"
			(at 157.48 243.84 0)
			(effects
				(font
					(size 1.27 1.27)
					(thickness 0.15)
				)
				(justify left bottom)
				(hide yes)
			)
		)
		(property "Author" "Antmicro"
			(at 154.94 243.84 0)
			(effects
				(font
					(size 1.27 1.27)
					(thickness 0.15)
				)
				(justify left bottom)
				(hide yes)
			)
		)
		(property "Tolerance" "1%"
			(at 172.72 243.84 0)
			(effects
				(font
					(size 1.27 1.27)
				)
				(justify left bottom)
				(hide yes)
			)
		)
		(pin "1"
		)
		(pin "2"
		)
		(instances
			(project "data-center-rdimm-ddr5-tester"
				(path ""
					(reference "R11")
					(unit 1)
				)
			)
		)
	)
	(symbol
		(lib_id "antmicroResistors0402:R_100R_0402")
		(at 353.06 125.73 270)
		(unit 1)
		(exclude_from_sim no)
		(in_bom no)
		(on_board yes)
		(dnp yes)
		(fields_autoplaced yes)
		(property "Reference" "R37"
			(at 355.6 127 90)
			(effects
				(font
					(size 1.27 1.27)
				)
				(justify left)
			)
		)
		(property "Value" "R_100R_0402"
			(at 340.36 146.05 0)
			(effects
				(font
					(size 1.27 1.27)
					(thickness 0.15)
				)
				(justify left bottom)
				(hide yes)
			)
		)
		(property "Footprint" "antmicro-footprints:R_0402_1005Metric_EIA"
			(at 337.82 146.05 0)
			(effects
				(font
					(size 1.27 1.27)
					(thickness 0.15)
				)
				(justify left bottom)
				(hide yes)
			)
		)
		(property "Datasheet" "https://www.bourns.com/docs/product-datasheets/cr.pdf"
			(at 335.28 146.05 0)
			(effects
				(font
					(size 1.27 1.27)
					(thickness 0.15)
				)
				(justify left bottom)
				(hide yes)
			)
		)
		(property "Description" ""
			(at 353.06 125.73 0)
			(effects
				(font
					(size 1.27 1.27)
				)
				(hide yes)
			)
		)
		(property "Manufacturer" "Bourns"
			(at 330.2 146.05 0)
			(effects
				(font
					(size 1.27 1.27)
					(thickness 0.15)
				)
				(justify left bottom)
				(hide yes)
			)
		)
		(property "MPN" "CR0402-FX-1000GLF"
			(at 332.74 146.05 0)
			(effects
				(font
					(size 1.27 1.27)
					(thickness 0.15)
				)
				(justify left bottom)
				(hide yes)
			)
		)
		(property "Val" "100R"
			(at 355.6 130.1749 90)
			(effects
				(font
					(size 1.27 1.27)
					(thickness 0.15)
				)
				(justify left)
			)
		)
		(property "License" "Apache-2.0"
			(at 327.66 146.05 0)
			(effects
				(font
					(size 1.27 1.27)
					(thickness 0.15)
				)
				(justify left bottom)
				(hide yes)
			)
		)
		(property "Author" "Antmicro"
			(at 325.12 146.05 0)
			(effects
				(font
					(size 1.27 1.27)
					(thickness 0.15)
				)
				(justify left bottom)
				(hide yes)
			)
		)
		(property "Tolerance" "1%"
			(at 342.9 146.05 0)
			(effects
				(font
					(size 1.27 1.27)
				)
				(justify left bottom)
				(hide yes)
			)
		)
		(pin "1"
		)
		(pin "2"
		)
		(instances
			(project "data-center-rdimm-ddr5-tester"
				(path ""
					(reference "R37")
					(unit 1)
				)
			)
		)
	)
	(symbol
		(lib_id "antmicropower:+1V8")
		(at 195.58 46.99 0)
		(unit 1)
		(exclude_from_sim no)
		(in_bom yes)
		(on_board yes)
		(dnp no)
		(fields_autoplaced yes)
		(property "Reference" "#PWR0364"
			(at 210.82 49.53 0)
			(effects
				(font
					(size 1.27 1.27)
					(thickness 0.15)
				)
				(justify left bottom)
				(hide yes)
			)
		)
		(property "Value" "+1V8"
			(at 195.58 41.91 0)
			(effects
				(font
					(size 1.27 1.27)
					(thickness 0.15)
				)
			)
		)
		(property "Footprint" ""
			(at 210.82 54.61 0)
			(effects
				(font
					(size 1.27 1.27)
					(thickness 0.15)
				)
				(justify left bottom)
				(hide yes)
			)
		)
		(property "Datasheet" ""
			(at 210.82 57.15 0)
			(effects
				(font
					(size 1.27 1.27)
					(thickness 0.15)
				)
				(justify left bottom)
				(hide yes)
			)
		)
		(property "Description" ""
			(at 195.58 46.99 0)
			(effects
				(font
					(size 1.27 1.27)
				)
				(hide yes)
			)
		)
		(property "Author" "Antmicro"
			(at 210.82 52.07 0)
			(effects
				(font
					(size 1.27 1.27)
					(thickness 0.15)
				)
				(justify left bottom)
				(hide yes)
			)
		)
		(property "License" "Apache-2.0"
			(at 210.82 54.61 0)
			(effects
				(font
					(size 1.27 1.27)
					(thickness 0.15)
				)
				(justify left bottom)
				(hide yes)
			)
		)
		(pin "1"
		)
		(instances
			(project "data-center-rdimm-ddr5-tester"
				(path ""
					(reference "#PWR0364")
					(unit 1)
				)
			)
		)
	)
	(symbol
		(lib_id "antmicropower:+3V3")
		(at 267.97 214.63 0)
		(unit 1)
		(exclude_from_sim no)
		(in_bom yes)
		(on_board yes)
		(dnp no)
		(fields_autoplaced yes)
		(property "Reference" "#PWR0184"
			(at 267.97 218.44 0)
			(effects
				(font
					(size 1.27 1.27)
				)
				(hide yes)
			)
		)
		(property "Value" "+3V3"
			(at 264.795 212.09 0)
			(effects
				(font
					(size 1.27 1.27)
					(thickness 0.15)
				)
				(justify left bottom)
			)
		)
		(property "Footprint" ""
			(at 283.21 222.25 0)
			(effects
				(font
					(size 1.27 1.27)
					(thickness 0.15)
				)
				(justify left bottom)
				(hide yes)
			)
		)
		(property "Datasheet" ""
			(at 283.21 224.79 0)
			(effects
				(font
					(size 1.27 1.27)
					(thickness 0.15)
				)
				(justify left bottom)
				(hide yes)
			)
		)
		(property "Description" ""
			(at 267.97 214.63 0)
			(effects
				(font
					(size 1.27 1.27)
				)
				(hide yes)
			)
		)
		(property "Author" "Antmicro"
			(at 283.21 217.17 0)
			(effects
				(font
					(size 1.27 1.27)
					(thickness 0.15)
				)
				(justify left bottom)
				(hide yes)
			)
		)
		(property "License" "Apache-2.0"
			(at 283.21 219.71 0)
			(effects
				(font
					(size 1.27 1.27)
					(thickness 0.15)
				)
				(justify left bottom)
				(hide yes)
			)
		)
		(pin "1"
		)
		(instances
			(project "data-center-rdimm-ddr5-tester"
				(path ""
					(reference "#PWR0184")
					(unit 1)
				)
			)
		)
	)
	(symbol
		(lib_id "antmicropower:GND")
		(at 208.28 152.4 0)
		(unit 1)
		(exclude_from_sim no)
		(in_bom yes)
		(on_board yes)
		(dnp no)
		(fields_autoplaced yes)
		(property "Reference" "#PWR0534"
			(at 208.28 158.75 0)
			(effects
				(font
					(size 1.27 1.27)
				)
				(hide yes)
			)
		)
		(property "Value" "GND"
			(at 206.375 156.845 0)
			(effects
				(font
					(size 1.27 1.27)
					(thickness 0.15)
				)
				(justify left bottom)
			)
		)
		(property "Footprint" ""
			(at 217.17 160.02 0)
			(effects
				(font
					(size 1.27 1.27)
					(thickness 0.15)
				)
				(justify left bottom)
				(hide yes)
			)
		)
		(property "Datasheet" ""
			(at 217.17 165.1 0)
			(effects
				(font
					(size 1.27 1.27)
					(thickness 0.15)
				)
				(justify left bottom)
				(hide yes)
			)
		)
		(property "Description" ""
			(at 208.28 152.4 0)
			(effects
				(font
					(size 1.27 1.27)
				)
				(hide yes)
			)
		)
		(property "Author" "Antmicro"
			(at 217.17 157.48 0)
			(effects
				(font
					(size 1.27 1.27)
					(thickness 0.15)
				)
				(justify left bottom)
				(hide yes)
			)
		)
		(property "License" "Apache-2.0"
			(at 217.17 160.02 0)
			(effects
				(font
					(size 1.27 1.27)
					(thickness 0.15)
				)
				(justify left bottom)
				(hide yes)
			)
		)
		(pin "1"
		)
		(instances
			(project "data-center-rdimm-ddr5-tester"
				(path ""
					(reference "#PWR0534")
					(unit 1)
				)
			)
		)
	)
	(symbol
		(lib_id "antmicropower:GND")
		(at 80.01 139.7 0)
		(mirror y)
		(unit 1)
		(exclude_from_sim no)
		(in_bom yes)
		(on_board yes)
		(dnp no)
		(fields_autoplaced yes)
		(property "Reference" "#PWR0374"
			(at 80.01 146.05 0)
			(effects
				(font
					(size 1.27 1.27)
				)
				(hide yes)
			)
		)
		(property "Value" "GND"
			(at 81.915 144.145 0)
			(effects
				(font
					(size 1.27 1.27)
					(thickness 0.15)
				)
				(justify left bottom)
			)
		)
		(property "Footprint" ""
			(at 71.12 147.32 0)
			(effects
				(font
					(size 1.27 1.27)
					(thickness 0.15)
				)
				(justify left bottom)
				(hide yes)
			)
		)
		(property "Datasheet" ""
			(at 71.12 152.4 0)
			(effects
				(font
					(size 1.27 1.27)
					(thickness 0.15)
				)
				(justify left bottom)
				(hide yes)
			)
		)
		(property "Description" ""
			(at 80.01 139.7 0)
			(effects
				(font
					(size 1.27 1.27)
				)
				(hide yes)
			)
		)
		(property "Author" "Antmicro"
			(at 71.12 144.78 0)
			(effects
				(font
					(size 1.27 1.27)
					(thickness 0.15)
				)
				(justify left bottom)
				(hide yes)
			)
		)
		(property "License" "Apache-2.0"
			(at 71.12 147.32 0)
			(effects
				(font
					(size 1.27 1.27)
					(thickness 0.15)
				)
				(justify left bottom)
				(hide yes)
			)
		)
		(pin "1"
		)
		(instances
			(project "data-center-rdimm-ddr5-tester"
				(path ""
					(reference "#PWR0374")
					(unit 1)
				)
			)
		)
	)
	(symbol
		(lib_id "antmicroLEDIndicationDiscrete:LED_G_0402_VLMTG1500-GS08")
		(at 224.79 222.25 90)
		(unit 1)
		(exclude_from_sim no)
		(in_bom yes)
		(on_board yes)
		(dnp no)
		(fields_autoplaced yes)
		(property "Reference" "D2"
			(at 226.695 218.44 90)
			(effects
				(font
					(size 1.27 1.27)
					(thickness 0.15)
				)
				(justify right)
			)
		)
		(property "Value" "LED_G_0402_VLMTG1500-GS08"
			(at 232.41 199.39 0)
			(effects
				(font
					(size 1.27 1.27)
					(thickness 0.15)
				)
				(justify left bottom)
				(hide yes)
			)
		)
		(property "Footprint" "antmicro-footprints:LED_0402_1005Metric_G"
			(at 234.95 199.39 0)
			(effects
				(font
					(size 1.27 1.27)
					(thickness 0.15)
				)
				(justify left bottom)
				(hide yes)
			)
		)
		(property "Datasheet" "https://www.vishay.com/docs/82554/vlmo1500.pdf"
			(at 237.49 199.39 0)
			(effects
				(font
					(size 1.27 1.27)
					(thickness 0.15)
				)
				(justify left bottom)
				(hide yes)
			)
		)
		(property "Description" ""
			(at 224.79 222.25 0)
			(effects
				(font
					(size 1.27 1.27)
				)
				(hide yes)
			)
		)
		(property "MPN" "VLMTG1500-GS08"
			(at 240.03 199.39 0)
			(effects
				(font
					(size 1.27 1.27)
					(thickness 0.15)
				)
				(justify left bottom)
				(hide yes)
			)
		)
		(property "Manufacturer" "Vishay"
			(at 242.57 199.39 0)
			(effects
				(font
					(size 1.27 1.27)
					(thickness 0.15)
				)
				(justify left bottom)
				(hide yes)
			)
		)
		(property "Color" "Green"
			(at 226.695 220.98 90)
			(effects
				(font
					(size 1.27 1.27)
				)
				(justify right)
			)
		)
		(property "Author" "Antmicro"
			(at 245.11 199.39 0)
			(effects
				(font
					(size 1.27 1.27)
					(thickness 0.15)
				)
				(justify left bottom)
				(hide yes)
			)
		)
		(property "License" "Apache-2.0"
			(at 247.65 199.39 0)
			(effects
				(font
					(size 1.27 1.27)
					(thickness 0.15)
				)
				(justify left bottom)
				(hide yes)
			)
		)
		(pin "1"
		)
		(pin "2"
		)
		(instances
			(project "data-center-rdimm-ddr5-tester"
				(path ""
					(reference "D2")
					(unit 1)
				)
			)
		)
	)
	(symbol
		(lib_id "antmicropower:+3V3")
		(at 54.61 224.79 0)
		(unit 1)
		(exclude_from_sim no)
		(in_bom yes)
		(on_board yes)
		(dnp no)
		(fields_autoplaced yes)
		(property "Reference" "#PWR0327"
			(at 54.61 228.6 0)
			(effects
				(font
					(size 1.27 1.27)
				)
				(hide yes)
			)
		)
		(property "Value" "+3V3"
			(at 51.435 222.25 0)
			(effects
				(font
					(size 1.27 1.27)
					(thickness 0.15)
				)
				(justify left bottom)
			)
		)
		(property "Footprint" ""
			(at 69.85 232.41 0)
			(effects
				(font
					(size 1.27 1.27)
					(thickness 0.15)
				)
				(justify left bottom)
				(hide yes)
			)
		)
		(property "Datasheet" ""
			(at 69.85 234.95 0)
			(effects
				(font
					(size 1.27 1.27)
					(thickness 0.15)
				)
				(justify left bottom)
				(hide yes)
			)
		)
		(property "Description" ""
			(at 54.61 224.79 0)
			(effects
				(font
					(size 1.27 1.27)
				)
				(hide yes)
			)
		)
		(property "Author" "Antmicro"
			(at 69.85 227.33 0)
			(effects
				(font
					(size 1.27 1.27)
					(thickness 0.15)
				)
				(justify left bottom)
				(hide yes)
			)
		)
		(property "License" "Apache-2.0"
			(at 69.85 229.87 0)
			(effects
				(font
					(size 1.27 1.27)
					(thickness 0.15)
				)
				(justify left bottom)
				(hide yes)
			)
		)
		(pin "1"
		)
		(instances
			(project "data-center-rdimm-ddr5-tester"
				(path ""
					(reference "#PWR0327")
					(unit 1)
				)
			)
		)
	)
	(symbol
		(lib_id "antmicropower:+3V3")
		(at 87.63 220.98 0)
		(unit 1)
		(exclude_from_sim no)
		(in_bom yes)
		(on_board yes)
		(dnp no)
		(fields_autoplaced yes)
		(property "Reference" "#PWR0181"
			(at 87.63 224.79 0)
			(effects
				(font
					(size 1.27 1.27)
				)
				(hide yes)
			)
		)
		(property "Value" "+3V3"
			(at 84.455 218.44 0)
			(effects
				(font
					(size 1.27 1.27)
					(thickness 0.15)
				)
				(justify left bottom)
			)
		)
		(property "Footprint" ""
			(at 102.87 228.6 0)
			(effects
				(font
					(size 1.27 1.27)
					(thickness 0.15)
				)
				(justify left bottom)
				(hide yes)
			)
		)
		(property "Datasheet" ""
			(at 102.87 231.14 0)
			(effects
				(font
					(size 1.27 1.27)
					(thickness 0.15)
				)
				(justify left bottom)
				(hide yes)
			)
		)
		(property "Description" ""
			(at 87.63 220.98 0)
			(effects
				(font
					(size 1.27 1.27)
				)
				(hide yes)
			)
		)
		(property "Author" "Antmicro"
			(at 102.87 223.52 0)
			(effects
				(font
					(size 1.27 1.27)
					(thickness 0.15)
				)
				(justify left bottom)
				(hide yes)
			)
		)
		(property "License" "Apache-2.0"
			(at 102.87 226.06 0)
			(effects
				(font
					(size 1.27 1.27)
					(thickness 0.15)
				)
				(justify left bottom)
				(hide yes)
			)
		)
		(pin "1"
		)
		(instances
			(project "data-center-rdimm-ddr5-tester"
				(path ""
					(reference "#PWR0181")
					(unit 1)
				)
			)
		)
	)
	(symbol
		(lib_id "antmicropower:+3V3")
		(at 63.5 224.79 0)
		(unit 1)
		(exclude_from_sim no)
		(in_bom yes)
		(on_board yes)
		(dnp no)
		(fields_autoplaced yes)
		(property "Reference" "#PWR0320"
			(at 63.5 228.6 0)
			(effects
				(font
					(size 1.27 1.27)
				)
				(hide yes)
			)
		)
		(property "Value" "+3V3"
			(at 60.325 222.25 0)
			(effects
				(font
					(size 1.27 1.27)
					(thickness 0.15)
				)
				(justify left bottom)
			)
		)
		(property "Footprint" ""
			(at 78.74 232.41 0)
			(effects
				(font
					(size 1.27 1.27)
					(thickness 0.15)
				)
				(justify left bottom)
				(hide yes)
			)
		)
		(property "Datasheet" ""
			(at 78.74 234.95 0)
			(effects
				(font
					(size 1.27 1.27)
					(thickness 0.15)
				)
				(justify left bottom)
				(hide yes)
			)
		)
		(property "Description" ""
			(at 63.5 224.79 0)
			(effects
				(font
					(size 1.27 1.27)
				)
				(hide yes)
			)
		)
		(property "Author" "Antmicro"
			(at 78.74 227.33 0)
			(effects
				(font
					(size 1.27 1.27)
					(thickness 0.15)
				)
				(justify left bottom)
				(hide yes)
			)
		)
		(property "License" "Apache-2.0"
			(at 78.74 229.87 0)
			(effects
				(font
					(size 1.27 1.27)
					(thickness 0.15)
				)
				(justify left bottom)
				(hide yes)
			)
		)
		(pin "1"
		)
		(instances
			(project "data-center-rdimm-ddr5-tester"
				(path ""
					(reference "#PWR0320")
					(unit 1)
				)
			)
		)
	)
	(symbol
		(lib_id "antmicropower:+1V8")
		(at 341.63 36.83 0)
		(unit 1)
		(exclude_from_sim no)
		(in_bom yes)
		(on_board yes)
		(dnp no)
		(fields_autoplaced yes)
		(property "Reference" "#PWR0185"
			(at 356.87 39.37 0)
			(effects
				(font
					(size 1.27 1.27)
					(thickness 0.15)
				)
				(justify left bottom)
				(hide yes)
			)
		)
		(property "Value" "+1V8"
			(at 341.63 31.75 0)
			(effects
				(font
					(size 1.27 1.27)
					(thickness 0.15)
				)
			)
		)
		(property "Footprint" ""
			(at 356.87 44.45 0)
			(effects
				(font
					(size 1.27 1.27)
					(thickness 0.15)
				)
				(justify left bottom)
				(hide yes)
			)
		)
		(property "Datasheet" ""
			(at 356.87 46.99 0)
			(effects
				(font
					(size 1.27 1.27)
					(thickness 0.15)
				)
				(justify left bottom)
				(hide yes)
			)
		)
		(property "Description" ""
			(at 341.63 36.83 0)
			(effects
				(font
					(size 1.27 1.27)
				)
				(hide yes)
			)
		)
		(property "Author" "Antmicro"
			(at 356.87 41.91 0)
			(effects
				(font
					(size 1.27 1.27)
					(thickness 0.15)
				)
				(justify left bottom)
				(hide yes)
			)
		)
		(property "License" "Apache-2.0"
			(at 356.87 44.45 0)
			(effects
				(font
					(size 1.27 1.27)
					(thickness 0.15)
				)
				(justify left bottom)
				(hide yes)
			)
		)
		(pin "1"
		)
		(instances
			(project "data-center-rdimm-ddr5-tester"
				(path ""
					(reference "#PWR0185")
					(unit 1)
				)
			)
		)
	)
	(symbol
		(lib_id "antmicroResistors0402:R_4k7_0402")
		(at 63.5 226.06 270)
		(unit 1)
		(exclude_from_sim no)
		(in_bom yes)
		(on_board yes)
		(dnp no)
		(fields_autoplaced yes)
		(property "Reference" "R20"
			(at 66.04 227.33 90)
			(effects
				(font
					(size 1.27 1.27)
					(thickness 0.15)
				)
				(justify left)
			)
		)
		(property "Value" "R_4k7_0402"
			(at 50.8 246.38 0)
			(effects
				(font
					(size 1.27 1.27)
					(thickness 0.15)
				)
				(justify left bottom)
				(hide yes)
			)
		)
		(property "Footprint" "antmicro-footprints:R_0402_1005Metric"
			(at 48.26 246.38 0)
			(effects
				(font
					(size 1.27 1.27)
					(thickness 0.15)
				)
				(justify left bottom)
				(hide yes)
			)
		)
		(property "Datasheet" "https://www.bourns.com/docs/product-datasheets/cr.pdf"
			(at 45.72 246.38 0)
			(effects
				(font
					(size 1.27 1.27)
					(thickness 0.15)
				)
				(justify left bottom)
				(hide yes)
			)
		)
		(property "Description" ""
			(at 63.5 226.06 0)
			(effects
				(font
					(size 1.27 1.27)
				)
				(hide yes)
			)
		)
		(property "MPN" "CR0402-FX-4701GLF"
			(at 43.18 246.38 0)
			(effects
				(font
					(size 1.27 1.27)
					(thickness 0.15)
				)
				(justify left bottom)
				(hide yes)
			)
		)
		(property "Manufacturer" "Bourns"
			(at 40.64 246.38 0)
			(effects
				(font
					(size 1.27 1.27)
					(thickness 0.15)
				)
				(justify left bottom)
				(hide yes)
			)
		)
		(property "License" "Apache-2.0"
			(at 38.1 246.38 0)
			(effects
				(font
					(size 1.27 1.27)
					(thickness 0.15)
				)
				(justify left bottom)
				(hide yes)
			)
		)
		(property "Author" "Antmicro"
			(at 35.56 246.38 0)
			(effects
				(font
					(size 1.27 1.27)
					(thickness 0.15)
				)
				(justify left bottom)
				(hide yes)
			)
		)
		(property "Val" "4k7"
			(at 66.04 229.87 90)
			(effects
				(font
					(size 1.27 1.27)
					(thickness 0.15)
				)
				(justify left)
			)
		)
		(property "Tolerance" "1%"
			(at 53.34 246.38 0)
			(effects
				(font
					(size 1.27 1.27)
				)
				(justify left bottom)
				(hide yes)
			)
		)
		(pin "2"
		)
		(pin "1"
		)
		(instances
			(project "data-center-rdimm-ddr5-tester"
				(path ""
					(reference "R20")
					(unit 1)
				)
			)
		)
	)
	(symbol
		(lib_id "antmicroLEDIndicationDiscrete:LED_G_0402_VLMTG1500-GS08")
		(at 182.88 222.25 90)
		(unit 1)
		(exclude_from_sim no)
		(in_bom yes)
		(on_board yes)
		(dnp no)
		(fields_autoplaced yes)
		(property "Reference" "D1"
			(at 184.785 218.44 90)
			(effects
				(font
					(size 1.27 1.27)
					(thickness 0.15)
				)
				(justify right)
			)
		)
		(property "Value" "LED_G_0402_VLMTG1500-GS08"
			(at 190.5 199.39 0)
			(effects
				(font
					(size 1.27 1.27)
					(thickness 0.15)
				)
				(justify left bottom)
				(hide yes)
			)
		)
		(property "Footprint" "antmicro-footprints:LED_0402_1005Metric_G"
			(at 193.04 199.39 0)
			(effects
				(font
					(size 1.27 1.27)
					(thickness 0.15)
				)
				(justify left bottom)
				(hide yes)
			)
		)
		(property "Datasheet" "https://www.vishay.com/docs/82554/vlmo1500.pdf"
			(at 195.58 199.39 0)
			(effects
				(font
					(size 1.27 1.27)
					(thickness 0.15)
				)
				(justify left bottom)
				(hide yes)
			)
		)
		(property "Description" ""
			(at 182.88 222.25 0)
			(effects
				(font
					(size 1.27 1.27)
				)
				(hide yes)
			)
		)
		(property "MPN" "VLMTG1500-GS08"
			(at 198.12 199.39 0)
			(effects
				(font
					(size 1.27 1.27)
					(thickness 0.15)
				)
				(justify left bottom)
				(hide yes)
			)
		)
		(property "Manufacturer" "Vishay"
			(at 200.66 199.39 0)
			(effects
				(font
					(size 1.27 1.27)
					(thickness 0.15)
				)
				(justify left bottom)
				(hide yes)
			)
		)
		(property "Color" "Green"
			(at 184.785 220.98 90)
			(effects
				(font
					(size 1.27 1.27)
				)
				(justify right)
			)
		)
		(property "Author" "Antmicro"
			(at 203.2 199.39 0)
			(effects
				(font
					(size 1.27 1.27)
					(thickness 0.15)
				)
				(justify left bottom)
				(hide yes)
			)
		)
		(property "License" "Apache-2.0"
			(at 205.74 199.39 0)
			(effects
				(font
					(size 1.27 1.27)
					(thickness 0.15)
				)
				(justify left bottom)
				(hide yes)
			)
		)
		(pin "1"
		)
		(pin "2"
		)
		(instances
			(project "data-center-rdimm-ddr5-tester"
				(path ""
					(reference "D1")
					(unit 1)
				)
			)
		)
	)
	(symbol
		(lib_id "antmicropower:+0V85")
		(at 353.06 119.38 0)
		(unit 1)
		(exclude_from_sim no)
		(in_bom yes)
		(on_board yes)
		(dnp no)
		(fields_autoplaced yes)
		(property "Reference" "#PWR0328"
			(at 353.06 123.19 0)
			(effects
				(font
					(size 1.27 1.27)
				)
				(hide yes)
			)
		)
		(property "Value" "+0V85"
			(at 353.06 114.935 0)
			(effects
				(font
					(size 1.27 1.27)
				)
			)
		)
		(property "Footprint" ""
			(at 353.06 119.38 0)
			(effects
				(font
					(size 1.27 1.27)
				)
				(hide yes)
			)
		)
		(property "Datasheet" ""
			(at 353.06 119.38 0)
			(effects
				(font
					(size 1.27 1.27)
				)
				(hide yes)
			)
		)
		(property "Description" ""
			(at 353.06 119.38 0)
			(effects
				(font
					(size 1.27 1.27)
				)
				(hide yes)
			)
		)
		(pin "1"
		)
		(instances
			(project "data-center-rdimm-ddr5-tester"
				(path ""
					(reference "#PWR0328")
					(unit 1)
				)
			)
		)
	)
	(symbol
		(lib_id "antmicroResistors0402:R_10k_0402")
		(at 337.82 217.17 270)
		(mirror x)
		(unit 1)
		(exclude_from_sim no)
		(in_bom yes)
		(on_board yes)
		(dnp no)
		(property "Reference" "R17"
			(at 336.55 213.995 90)
			(effects
				(font
					(size 1.27 1.27)
					(thickness 0.15)
				)
				(justify right)
			)
		)
		(property "Value" "R_10k_0402"
			(at 325.12 196.85 0)
			(effects
				(font
					(size 1.27 1.27)
					(thickness 0.15)
				)
				(justify left bottom)
				(hide yes)
			)
		)
		(property "Footprint" "antmicro-footprints:R_0402_1005Metric_EIA"
			(at 322.58 196.85 0)
			(effects
				(font
					(size 1.27 1.27)
					(thickness 0.15)
				)
				(justify left bottom)
				(hide yes)
			)
		)
		(property "Datasheet" "https://www.bourns.com/docs/product-datasheets/cr.pdf"
			(at 320.04 196.85 0)
			(effects
				(font
					(size 1.27 1.27)
					(thickness 0.15)
				)
				(justify left bottom)
				(hide yes)
			)
		)
		(property "Description" ""
			(at 337.82 217.17 0)
			(effects
				(font
					(size 1.27 1.27)
				)
				(hide yes)
			)
		)
		(property "MPN" "CR0402-FX-1002GLF"
			(at 317.5 196.85 0)
			(effects
				(font
					(size 1.27 1.27)
					(thickness 0.15)
				)
				(justify left bottom)
				(hide yes)
			)
		)
		(property "Manufacturer" "Bourns"
			(at 314.96 196.85 0)
			(effects
				(font
					(size 1.27 1.27)
					(thickness 0.15)
				)
				(justify left bottom)
				(hide yes)
			)
		)
		(property "License" "Apache-2.0"
			(at 312.42 196.85 0)
			(effects
				(font
					(size 1.27 1.27)
					(thickness 0.15)
				)
				(justify left bottom)
				(hide yes)
			)
		)
		(property "Author" "Antmicro"
			(at 309.88 196.85 0)
			(effects
				(font
					(size 1.27 1.27)
					(thickness 0.15)
				)
				(justify left bottom)
				(hide yes)
			)
		)
		(property "Val" "10k"
			(at 336.169 216.3231 90)
			(effects
				(font
					(size 1.27 1.27)
					(thickness 0.15)
				)
				(justify right)
			)
		)
		(property "Tolerance" "1%"
			(at 327.66 196.85 0)
			(effects
				(font
					(size 1.27 1.27)
				)
				(justify left bottom)
				(hide yes)
			)
		)
		(pin "1"
		)
		(pin "2"
		)
		(instances
			(project "data-center-rdimm-ddr5-tester"
				(path ""
					(reference "R17")
					(unit 1)
				)
			)
		)
	)
	(symbol
		(lib_id "antmicropower:GND")
		(at 107.95 238.76 0)
		(mirror y)
		(unit 1)
		(exclude_from_sim no)
		(in_bom yes)
		(on_board yes)
		(dnp no)
		(fields_autoplaced yes)
		(property "Reference" "#PWR0179"
			(at 107.95 245.11 0)
			(effects
				(font
					(size 1.27 1.27)
				)
				(hide yes)
			)
		)
		(property "Value" "GND"
			(at 109.855 243.205 0)
			(effects
				(font
					(size 1.27 1.27)
					(thickness 0.15)
				)
				(justify left bottom)
			)
		)
		(property "Footprint" ""
			(at 99.06 246.38 0)
			(effects
				(font
					(size 1.27 1.27)
					(thickness 0.15)
				)
				(justify left bottom)
				(hide yes)
			)
		)
		(property "Datasheet" ""
			(at 99.06 251.46 0)
			(effects
				(font
					(size 1.27 1.27)
					(thickness 0.15)
				)
				(justify left bottom)
				(hide yes)
			)
		)
		(property "Description" ""
			(at 107.95 238.76 0)
			(effects
				(font
					(size 1.27 1.27)
				)
				(hide yes)
			)
		)
		(property "Author" "Antmicro"
			(at 99.06 243.84 0)
			(effects
				(font
					(size 1.27 1.27)
					(thickness 0.15)
				)
				(justify left bottom)
				(hide yes)
			)
		)
		(property "License" "Apache-2.0"
			(at 99.06 246.38 0)
			(effects
				(font
					(size 1.27 1.27)
					(thickness 0.15)
				)
				(justify left bottom)
				(hide yes)
			)
		)
		(pin "1"
		)
		(instances
			(project "data-center-rdimm-ddr5-tester"
				(path ""
					(reference "#PWR0179")
					(unit 1)
				)
			)
		)
	)
	(symbol
		(lib_id "antmicropower:+1V8")
		(at 346.71 208.28 0)
		(unit 1)
		(exclude_from_sim no)
		(in_bom yes)
		(on_board yes)
		(dnp no)
		(fields_autoplaced yes)
		(property "Reference" "#PWR021"
			(at 361.95 210.82 0)
			(effects
				(font
					(size 1.27 1.27)
					(thickness 0.15)
				)
				(justify left bottom)
				(hide yes)
			)
		)
		(property "Value" "+1V8"
			(at 346.71 203.2 0)
			(effects
				(font
					(size 1.27 1.27)
					(thickness 0.15)
				)
			)
		)
		(property "Footprint" ""
			(at 361.95 215.9 0)
			(effects
				(font
					(size 1.27 1.27)
					(thickness 0.15)
				)
				(justify left bottom)
				(hide yes)
			)
		)
		(property "Datasheet" ""
			(at 361.95 218.44 0)
			(effects
				(font
					(size 1.27 1.27)
					(thickness 0.15)
				)
				(justify left bottom)
				(hide yes)
			)
		)
		(property "Description" ""
			(at 346.71 208.28 0)
			(effects
				(font
					(size 1.27 1.27)
				)
				(hide yes)
			)
		)
		(property "Author" "Antmicro"
			(at 361.95 213.36 0)
			(effects
				(font
					(size 1.27 1.27)
					(thickness 0.15)
				)
				(justify left bottom)
				(hide yes)
			)
		)
		(property "License" "Apache-2.0"
			(at 361.95 215.9 0)
			(effects
				(font
					(size 1.27 1.27)
					(thickness 0.15)
				)
				(justify left bottom)
				(hide yes)
			)
		)
		(pin "1"
		)
		(instances
			(project "data-center-rdimm-ddr5-tester"
				(path ""
					(reference "#PWR021")
					(unit 1)
				)
			)
		)
	)
	(symbol
		(lib_id "antmicroGenericPinHeaders:PinHeader_2x7_P2mm_SMD_Shrouded_no-locator")
		(at 326.39 40.64 0)
		(unit 1)
		(exclude_from_sim no)
		(in_bom no)
		(on_board yes)
		(dnp yes)
		(property "Reference" "J1"
			(at 331.47 34.925 0)
			(effects
				(font
					(size 1.27 1.27)
				)
			)
		)
		(property "Value" "PinHeader_2x7_P2mm_SMD_Shrouded_no-locator"
			(at 351.79 45.72 0)
			(effects
				(font
					(size 1.27 1.27)
					(thickness 0.15)
				)
				(justify left bottom)
				(hide yes)
			)
		)
		(property "Footprint" "antmicro-footprints:PinHeader_2x7_P2mm_SMD_Shrouded_no-locator"
			(at 351.79 48.26 0)
			(effects
				(font
					(size 1.27 1.27)
					(thickness 0.15)
				)
				(justify left bottom)
				(hide yes)
			)
		)
		(property "Datasheet" "https://www.molex.com/pdm_docs/ps/PS-87831-027-001.pdf"
			(at 351.79 50.8 0)
			(effects
				(font
					(size 1.27 1.27)
					(thickness 0.15)
				)
				(justify left bottom)
				(hide yes)
			)
		)
		(property "Description" ""
			(at 326.39 40.64 0)
			(effects
				(font
					(size 1.27 1.27)
				)
				(hide yes)
			)
		)
		(property "MPN" "878321412"
			(at 331.47 37.465 0)
			(effects
				(font
					(size 1.27 1.27)
					(thickness 0.15)
				)
			)
		)
		(property "Manufacturer" "Molex"
			(at 351.79 55.88 0)
			(effects
				(font
					(size 1.27 1.27)
					(thickness 0.15)
				)
				(justify left bottom)
				(hide yes)
			)
		)
		(property "Author" "Antmicro"
			(at 351.79 58.42 0)
			(effects
				(font
					(size 1.27 1.27)
					(thickness 0.15)
				)
				(justify left bottom)
				(hide yes)
			)
		)
		(property "License" "Apache-2.0"
			(at 351.79 60.96 0)
			(effects
				(font
					(size 1.27 1.27)
					(thickness 0.15)
				)
				(justify left bottom)
				(hide yes)
			)
		)
		(pin "1"
		)
		(pin "10"
		)
		(pin "11"
		)
		(pin "12"
		)
		(pin "13"
		)
		(pin "14"
		)
		(pin "2"
		)
		(pin "3"
		)
		(pin "4"
		)
		(pin "5"
		)
		(pin "6"
		)
		(pin "7"
		)
		(pin "8"
		)
		(pin "9"
		)
		(instances
			(project "data-center-rdimm-ddr5-tester"
				(path ""
					(reference "J1")
					(unit 1)
				)
			)
		)
	)
	(symbol
		(lib_id "antmicropower:GND")
		(at 334.01 143.51 0)
		(unit 1)
		(exclude_from_sim no)
		(in_bom yes)
		(on_board yes)
		(dnp no)
		(fields_autoplaced yes)
		(property "Reference" "#PWR023"
			(at 334.01 149.86 0)
			(effects
				(font
					(size 1.27 1.27)
				)
				(hide yes)
			)
		)
		(property "Value" "GND"
			(at 332.105 147.955 0)
			(effects
				(font
					(size 1.27 1.27)
					(thickness 0.15)
				)
				(justify left bottom)
			)
		)
		(property "Footprint" ""
			(at 342.9 151.13 0)
			(effects
				(font
					(size 1.27 1.27)
					(thickness 0.15)
				)
				(justify left bottom)
				(hide yes)
			)
		)
		(property "Datasheet" ""
			(at 342.9 156.21 0)
			(effects
				(font
					(size 1.27 1.27)
					(thickness 0.15)
				)
				(justify left bottom)
				(hide yes)
			)
		)
		(property "Description" ""
			(at 334.01 143.51 0)
			(effects
				(font
					(size 1.27 1.27)
				)
				(hide yes)
			)
		)
		(property "Author" "Antmicro"
			(at 342.9 148.59 0)
			(effects
				(font
					(size 1.27 1.27)
					(thickness 0.15)
				)
				(justify left bottom)
				(hide yes)
			)
		)
		(property "License" "Apache-2.0"
			(at 342.9 151.13 0)
			(effects
				(font
					(size 1.27 1.27)
					(thickness 0.15)
				)
				(justify left bottom)
				(hide yes)
			)
		)
		(pin "1"
		)
		(instances
			(project "data-center-rdimm-ddr5-tester"
				(path ""
					(reference "#PWR023")
					(unit 1)
				)
			)
		)
	)
	(symbol
		(lib_id "antmicroShuntsJumpers:Net-Tie_P0.127mm")
		(at 245.11 52.07 0)
		(unit 1)
		(exclude_from_sim no)
		(in_bom no)
		(on_board yes)
		(dnp no)
		(property "Reference" "TP4"
			(at 247.65 49.53 0)
			(effects
				(font
					(size 1.27 1.27)
					(thickness 0.15)
				)
			)
		)
		(property "Value" "Net-Tie_P0.127mm"
			(at 248.285 49.53 0)
			(effects
				(font
					(size 1.27 1.27)
					(thickness 0.15)
				)
				(hide yes)
			)
		)
		(property "Footprint" "antmicro-footprints:NetTie-2_SMD_Pad0.127mm"
			(at 266.7 64.77 0)
			(effects
				(font
					(size 1.27 1.27)
					(thickness 0.15)
				)
				(justify left bottom)
				(hide yes)
			)
		)
		(property "Datasheet" ""
			(at 266.7 67.31 0)
			(effects
				(font
					(size 1.27 1.27)
					(thickness 0.15)
				)
				(justify left bottom)
				(hide yes)
			)
		)
		(property "Description" ""
			(at 245.11 52.07 0)
			(effects
				(font
					(size 1.27 1.27)
				)
				(hide yes)
			)
		)
		(property "MPN" ""
			(at 266.7 62.23 0)
			(effects
				(font
					(size 1.27 1.27)
					(thickness 0.15)
				)
				(justify left bottom)
			)
		)
		(property "Manufacturer" ""
			(at 266.7 69.85 0)
			(effects
				(font
					(size 1.27 1.27)
					(thickness 0.15)
				)
				(justify left bottom)
				(hide yes)
			)
		)
		(property "Author" "Antmicro"
			(at 266.7 72.39 0)
			(effects
				(font
					(size 1.27 1.27)
					(thickness 0.15)
				)
				(justify left bottom)
				(hide yes)
			)
		)
		(property "License" "Apache-2.0"
			(at 266.7 74.93 0)
			(effects
				(font
					(size 1.27 1.27)
					(thickness 0.15)
				)
				(justify left bottom)
				(hide yes)
			)
		)
		(pin "2"
		)
		(pin "1"
		)
		(instances
			(project "data-center-rdimm-ddr5-tester"
				(path ""
					(reference "TP4")
					(unit 1)
				)
			)
		)
	)
	(symbol
		(lib_id "antmicropower:GND")
		(at 231.14 60.96 0)
		(unit 1)
		(exclude_from_sim no)
		(in_bom yes)
		(on_board yes)
		(dnp no)
		(fields_autoplaced yes)
		(property "Reference" "#PWR018"
			(at 231.14 67.31 0)
			(effects
				(font
					(size 1.27 1.27)
				)
				(hide yes)
			)
		)
		(property "Value" "GND"
			(at 229.235 65.405 0)
			(effects
				(font
					(size 1.27 1.27)
					(thickness 0.15)
				)
				(justify left bottom)
			)
		)
		(property "Footprint" ""
			(at 240.03 68.58 0)
			(effects
				(font
					(size 1.27 1.27)
					(thickness 0.15)
				)
				(justify left bottom)
				(hide yes)
			)
		)
		(property "Datasheet" ""
			(at 240.03 73.66 0)
			(effects
				(font
					(size 1.27 1.27)
					(thickness 0.15)
				)
				(justify left bottom)
				(hide yes)
			)
		)
		(property "Description" ""
			(at 231.14 60.96 0)
			(effects
				(font
					(size 1.27 1.27)
				)
				(hide yes)
			)
		)
		(property "Author" "Antmicro"
			(at 240.03 66.04 0)
			(effects
				(font
					(size 1.27 1.27)
					(thickness 0.15)
				)
				(justify left bottom)
				(hide yes)
			)
		)
		(property "License" "Apache-2.0"
			(at 240.03 68.58 0)
			(effects
				(font
					(size 1.27 1.27)
					(thickness 0.15)
				)
				(justify left bottom)
				(hide yes)
			)
		)
		(pin "1"
		)
		(instances
			(project "data-center-rdimm-ddr5-tester"
				(path ""
					(reference "#PWR018")
					(unit 1)
				)
			)
		)
	)
	(symbol
		(lib_id "antmicroResistors0402:R_100R_0402")
		(at 353.06 138.43 270)
		(unit 1)
		(exclude_from_sim no)
		(in_bom yes)
		(on_board yes)
		(dnp no)
		(property "Reference" "R194"
			(at 355.6 139.7 90)
			(effects
				(font
					(size 1.27 1.27)
				)
				(justify left)
			)
		)
		(property "Value" "R_100R_0402"
			(at 340.36 158.75 0)
			(effects
				(font
					(size 1.27 1.27)
					(thickness 0.15)
				)
				(justify left bottom)
				(hide yes)
			)
		)
		(property "Footprint" "antmicro-footprints:R_0402_1005Metric_EIA"
			(at 337.82 158.75 0)
			(effects
				(font
					(size 1.27 1.27)
					(thickness 0.15)
				)
				(justify left bottom)
				(hide yes)
			)
		)
		(property "Datasheet" "https://www.bourns.com/docs/product-datasheets/cr.pdf"
			(at 335.28 158.75 0)
			(effects
				(font
					(size 1.27 1.27)
					(thickness 0.15)
				)
				(justify left bottom)
				(hide yes)
			)
		)
		(property "Description" ""
			(at 353.06 138.43 0)
			(effects
				(font
					(size 1.27 1.27)
				)
				(hide yes)
			)
		)
		(property "Manufacturer" "Bourns"
			(at 330.2 158.75 0)
			(effects
				(font
					(size 1.27 1.27)
					(thickness 0.15)
				)
				(justify left bottom)
				(hide yes)
			)
		)
		(property "MPN" "CR0402-FX-1000GLF"
			(at 332.74 158.75 0)
			(effects
				(font
					(size 1.27 1.27)
					(thickness 0.15)
				)
				(justify left bottom)
				(hide yes)
			)
		)
		(property "Val" "100R"
			(at 355.6 142.8749 90)
			(effects
				(font
					(size 1.27 1.27)
					(thickness 0.15)
				)
				(justify left)
			)
		)
		(property "License" "Apache-2.0"
			(at 327.66 158.75 0)
			(effects
				(font
					(size 1.27 1.27)
					(thickness 0.15)
				)
				(justify left bottom)
				(hide yes)
			)
		)
		(property "Author" "Antmicro"
			(at 325.12 158.75 0)
			(effects
				(font
					(size 1.27 1.27)
					(thickness 0.15)
				)
				(justify left bottom)
				(hide yes)
			)
		)
		(property "Tolerance" "1%"
			(at 342.9 158.75 0)
			(effects
				(font
					(size 1.27 1.27)
				)
				(justify left bottom)
				(hide yes)
			)
		)
		(pin "1"
		)
		(pin "2"
		)
		(instances
			(project "data-center-rdimm-ddr5-tester"
				(path ""
					(reference "R194")
					(unit 1)
				)
			)
		)
	)
	(symbol
		(lib_id "antmicroResistors0402:R_100R_0402")
		(at 334.01 125.73 270)
		(unit 1)
		(exclude_from_sim no)
		(in_bom yes)
		(on_board yes)
		(dnp no)
		(fields_autoplaced yes)
		(property "Reference" "R21"
			(at 336.55 127 90)
			(effects
				(font
					(size 1.27 1.27)
				)
				(justify left)
			)
		)
		(property "Value" "R_100R_0402"
			(at 321.31 146.05 0)
			(effects
				(font
					(size 1.27 1.27)
					(thickness 0.15)
				)
				(justify left bottom)
				(hide yes)
			)
		)
		(property "Footprint" "antmicro-footprints:R_0402_1005Metric_EIA"
			(at 318.77 146.05 0)
			(effects
				(font
					(size 1.27 1.27)
					(thickness 0.15)
				)
				(justify left bottom)
				(hide yes)
			)
		)
		(property "Datasheet" "https://www.bourns.com/docs/product-datasheets/cr.pdf"
			(at 316.23 146.05 0)
			(effects
				(font
					(size 1.27 1.27)
					(thickness 0.15)
				)
				(justify left bottom)
				(hide yes)
			)
		)
		(property "Description" ""
			(at 334.01 125.73 0)
			(effects
				(font
					(size 1.27 1.27)
				)
				(hide yes)
			)
		)
		(property "Manufacturer" "Bourns"
			(at 311.15 146.05 0)
			(effects
				(font
					(size 1.27 1.27)
					(thickness 0.15)
				)
				(justify left bottom)
				(hide yes)
			)
		)
		(property "MPN" "CR0402-FX-1000GLF"
			(at 313.69 146.05 0)
			(effects
				(font
					(size 1.27 1.27)
					(thickness 0.15)
				)
				(justify left bottom)
				(hide yes)
			)
		)
		(property "Val" "100R"
			(at 336.55 130.1749 90)
			(effects
				(font
					(size 1.27 1.27)
					(thickness 0.15)
				)
				(justify left)
			)
		)
		(property "License" "Apache-2.0"
			(at 308.61 146.05 0)
			(effects
				(font
					(size 1.27 1.27)
					(thickness 0.15)
				)
				(justify left bottom)
				(hide yes)
			)
		)
		(property "Author" "Antmicro"
			(at 306.07 146.05 0)
			(effects
				(font
					(size 1.27 1.27)
					(thickness 0.15)
				)
				(justify left bottom)
				(hide yes)
			)
		)
		(property "Tolerance" "1%"
			(at 323.85 146.05 0)
			(effects
				(font
					(size 1.27 1.27)
				)
				(justify left bottom)
				(hide yes)
			)
		)
		(pin "1"
		)
		(pin "2"
		)
		(instances
			(project "data-center-rdimm-ddr5-tester"
				(path ""
					(reference "R21")
					(unit 1)
				)
			)
		)
	)
	(symbol
		(lib_name "REF3012AIDBZT_1")
		(lib_id "antmicroPMICPowerDistributionSwitchesLoadDrivers:REF3012AIDBZT")
		(at 208.28 48.26 0)
		(unit 1)
		(exclude_from_sim no)
		(in_bom yes)
		(on_board yes)
		(dnp no)
		(fields_autoplaced yes)
		(property "Reference" "U30"
			(at 217.17 41.91 0)
			(effects
				(font
					(size 1.27 1.27)
					(thickness 0.15)
				)
			)
		)
		(property "Value" "REF3012AIDBZT"
			(at 241.3 63.5 0)
			(effects
				(font
					(size 1.27 1.27)
					(thickness 0.15)
				)
				(justify left bottom)
				(hide yes)
			)
		)
		(property "Footprint" "antmicro-footprints:SOT-23-3"
			(at 241.3 58.42 0)
			(effects
				(font
					(size 1.27 1.27)
					(thickness 0.15)
				)
				(justify left bottom)
				(hide yes)
			)
		)
		(property "Datasheet" "https://www.ti.com/lit/gpn/REF3012"
			(at 241.3 60.96 0)
			(effects
				(font
					(size 1.27 1.27)
					(thickness 0.15)
				)
				(justify left bottom)
				(hide yes)
			)
		)
		(property "Description" ""
			(at 208.28 48.26 0)
			(effects
				(font
					(size 1.27 1.27)
				)
				(hide yes)
			)
		)
		(property "MPN" "REF3012AIDBZT"
			(at 217.17 44.45 0)
			(effects
				(font
					(size 1.27 1.27)
					(thickness 0.15)
				)
			)
		)
		(property "Manufacturer" "Texas Instruments"
			(at 241.3 66.04 0)
			(effects
				(font
					(size 1.27 1.27)
					(thickness 0.15)
				)
				(justify left bottom)
				(hide yes)
			)
		)
		(property "Author" "Antmicro"
			(at 241.3 68.58 0)
			(effects
				(font
					(size 1.27 1.27)
					(thickness 0.15)
				)
				(justify left bottom)
				(hide yes)
			)
		)
		(property "License" "Apache-2.0"
			(at 241.3 71.12 0)
			(effects
				(font
					(size 1.27 1.27)
					(thickness 0.15)
				)
				(justify left bottom)
				(hide yes)
			)
		)
		(pin "3"
		)
		(pin "2"
		)
		(pin "1"
		)
		(instances
			(project "data-center-rdimm-ddr5-tester"
				(path ""
					(reference "U30")
					(unit 1)
				)
			)
		)
	)
	(symbol
		(lib_id "antmicroCapacitors0402:C_1u_0402")
		(at 195.58 55.88 90)
		(unit 1)
		(exclude_from_sim no)
		(in_bom yes)
		(on_board yes)
		(dnp no)
		(fields_autoplaced yes)
		(property "Reference" "C204"
			(at 198.755 52.0636 90)
			(effects
				(font
					(size 1.27 1.27)
					(thickness 0.15)
				)
				(justify right)
			)
		)
		(property "Value" "C_1u_0402"
			(at 205.74 35.56 0)
			(effects
				(font
					(size 1.27 1.27)
					(thickness 0.15)
				)
				(justify left bottom)
				(hide yes)
			)
		)
		(property "Footprint" "antmicro-footprints:C_0402_1005Metric"
			(at 208.28 35.56 0)
			(effects
				(font
					(size 1.27 1.27)
					(thickness 0.15)
				)
				(justify left bottom)
				(hide yes)
			)
		)
		(property "Datasheet" "https://product.tdk.com/en/search/capacitor/ceramic/mlcc/info?part_no=C1005X6S1A105K050BC"
			(at 210.82 35.56 0)
			(effects
				(font
					(size 1.27 1.27)
					(thickness 0.15)
				)
				(justify left bottom)
				(hide yes)
			)
		)
		(property "Description" ""
			(at 195.58 55.88 0)
			(effects
				(font
					(size 1.27 1.27)
				)
				(hide yes)
			)
		)
		(property "MPN" "C1005X6S1A105K050BC"
			(at 213.36 35.56 0)
			(effects
				(font
					(size 1.27 1.27)
					(thickness 0.15)
				)
				(justify left bottom)
				(hide yes)
			)
		)
		(property "Manufacturer" "TDK"
			(at 215.9 35.56 0)
			(effects
				(font
					(size 1.27 1.27)
					(thickness 0.15)
				)
				(justify left bottom)
				(hide yes)
			)
		)
		(property "License" "Apache-2.0"
			(at 218.44 35.56 0)
			(effects
				(font
					(size 1.27 1.27)
					(thickness 0.15)
				)
				(justify left bottom)
				(hide yes)
			)
		)
		(property "Author" "Antmicro"
			(at 220.98 35.56 0)
			(effects
				(font
					(size 1.27 1.27)
					(thickness 0.15)
				)
				(justify left bottom)
				(hide yes)
			)
		)
		(property "Val" "1u"
			(at 198.755 54.6036 90)
			(effects
				(font
					(size 1.27 1.27)
					(thickness 0.15)
				)
				(justify right)
			)
		)
		(property "Voltage" ""
			(at 223.52 35.56 0)
			(effects
				(font
					(size 1.27 1.27)
				)
				(justify left bottom)
				(hide yes)
			)
		)
		(property "Dielectric" ""
			(at 226.06 35.56 0)
			(effects
				(font
					(size 1.27 1.27)
				)
				(justify left bottom)
				(hide yes)
			)
		)
		(pin "2"
		)
		(pin "1"
		)
		(instances
			(project "data-center-rdimm-ddr5-tester"
				(path ""
					(reference "C204")
					(unit 1)
				)
			)
		)
	)
	(symbol
		(lib_id "antmicroTVSDiodes:TPD4E05U06QDQARQ1")
		(at 382.27 43.18 0)
		(mirror y)
		(unit 1)
		(exclude_from_sim no)
		(in_bom yes)
		(on_board yes)
		(dnp no)
		(property "Reference" "U2"
			(at 372.11 46.355 0)
			(effects
				(font
					(size 1.27 1.27)
					(thickness 0.15)
				)
				(justify left)
			)
		)
		(property "Value" "TPD4E05U06QDQARQ1"
			(at 358.14 53.34 0)
			(effects
				(font
					(size 1.27 1.27)
					(thickness 0.15)
				)
				(justify left bottom)
				(hide yes)
			)
		)
		(property "Footprint" "antmicro-footprints:USON-10_2.5x1mm_P0.5mm"
			(at 358.14 48.26 0)
			(effects
				(font
					(size 1.27 1.27)
					(thickness 0.15)
				)
				(justify left bottom)
				(hide yes)
			)
		)
		(property "Datasheet" "https://www.ti.com/lit/ds/symlink/tpd4e05u06-q1.pdf?HQS=dis-mous-null-mousermode-dsf-pf-null-wwe&ts=1663591265741&ref_url=https%253A%252F%252Fwww.mouser.com%252F"
			(at 358.14 50.8 0)
			(effects
				(font
					(size 1.27 1.27)
					(thickness 0.15)
				)
				(justify left bottom)
				(hide yes)
			)
		)
		(property "Description" ""
			(at 382.27 43.18 0)
			(effects
				(font
					(size 1.27 1.27)
				)
				(hide yes)
			)
		)
		(property "MPN" "TPD4E05U06QDQARQ1"
			(at 372.11 48.895 0)
			(effects
				(font
					(size 1.27 1.27)
					(thickness 0.15)
				)
				(justify left)
			)
		)
		(property "Manufacturer" "Texas Instruments"
			(at 358.14 55.88 0)
			(effects
				(font
					(size 1.27 1.27)
					(thickness 0.15)
				)
				(justify left bottom)
				(hide yes)
			)
		)
		(property "Author" "Antmicro"
			(at 358.14 58.42 0)
			(effects
				(font
					(size 1.27 1.27)
					(thickness 0.15)
				)
				(justify left bottom)
				(hide yes)
			)
		)
		(property "License" "Apache-2.0"
			(at 358.14 60.96 0)
			(effects
				(font
					(size 1.27 1.27)
					(thickness 0.15)
				)
				(justify left bottom)
				(hide yes)
			)
		)
		(pin "10"
		)
		(pin "2"
		)
		(pin "3"
		)
		(pin "5"
		)
		(pin "7"
		)
		(pin "8"
		)
		(pin "1"
		)
		(pin "9"
		)
		(pin "6"
		)
		(pin "4"
		)
		(instances
			(project "data-center-rdimm-ddr5-tester"
				(path ""
					(reference "U2")
					(unit 1)
				)
			)
		)
	)
	(symbol
		(lib_id "antmicroLEDIndicationDiscrete:LED_G_0402_VLMTG1500-GS08")
		(at 267.97 222.25 90)
		(unit 1)
		(exclude_from_sim no)
		(in_bom yes)
		(on_board yes)
		(dnp no)
		(fields_autoplaced yes)
		(property "Reference" "D3"
			(at 269.875 218.44 90)
			(effects
				(font
					(size 1.27 1.27)
					(thickness 0.15)
				)
				(justify right)
			)
		)
		(property "Value" "LED_G_0402_VLMTG1500-GS08"
			(at 275.59 199.39 0)
			(effects
				(font
					(size 1.27 1.27)
					(thickness 0.15)
				)
				(justify left bottom)
				(hide yes)
			)
		)
		(property "Footprint" "antmicro-footprints:LED_0402_1005Metric_G"
			(at 278.13 199.39 0)
			(effects
				(font
					(size 1.27 1.27)
					(thickness 0.15)
				)
				(justify left bottom)
				(hide yes)
			)
		)
		(property "Datasheet" "https://www.vishay.com/docs/82554/vlmo1500.pdf"
			(at 280.67 199.39 0)
			(effects
				(font
					(size 1.27 1.27)
					(thickness 0.15)
				)
				(justify left bottom)
				(hide yes)
			)
		)
		(property "Description" ""
			(at 267.97 222.25 0)
			(effects
				(font
					(size 1.27 1.27)
				)
				(hide yes)
			)
		)
		(property "MPN" "VLMTG1500-GS08"
			(at 283.21 199.39 0)
			(effects
				(font
					(size 1.27 1.27)
					(thickness 0.15)
				)
				(justify left bottom)
				(hide yes)
			)
		)
		(property "Manufacturer" "Vishay"
			(at 285.75 199.39 0)
			(effects
				(font
					(size 1.27 1.27)
					(thickness 0.15)
				)
				(justify left bottom)
				(hide yes)
			)
		)
		(property "Color" "Green"
			(at 269.875 220.98 90)
			(effects
				(font
					(size 1.27 1.27)
				)
				(justify right)
			)
		)
		(property "Author" "Antmicro"
			(at 288.29 199.39 0)
			(effects
				(font
					(size 1.27 1.27)
					(thickness 0.15)
				)
				(justify left bottom)
				(hide yes)
			)
		)
		(property "License" "Apache-2.0"
			(at 290.83 199.39 0)
			(effects
				(font
					(size 1.27 1.27)
					(thickness 0.15)
				)
				(justify left bottom)
				(hide yes)
			)
		)
		(pin "1"
		)
		(pin "2"
		)
		(instances
			(project "data-center-rdimm-ddr5-tester"
				(path ""
					(reference "D3")
					(unit 1)
				)
			)
		)
	)
	(symbol
		(lib_id "antmicropower:+3V3")
		(at 182.88 213.36 0)
		(unit 1)
		(exclude_from_sim no)
		(in_bom yes)
		(on_board yes)
		(dnp no)
		(fields_autoplaced yes)
		(property "Reference" "#PWR0176"
			(at 182.88 217.17 0)
			(effects
				(font
					(size 1.27 1.27)
				)
				(hide yes)
			)
		)
		(property "Value" "+3V3"
			(at 179.705 210.82 0)
			(effects
				(font
					(size 1.27 1.27)
					(thickness 0.15)
				)
				(justify left bottom)
			)
		)
		(property "Footprint" ""
			(at 198.12 220.98 0)
			(effects
				(font
					(size 1.27 1.27)
					(thickness 0.15)
				)
				(justify left bottom)
				(hide yes)
			)
		)
		(property "Datasheet" ""
			(at 198.12 223.52 0)
			(effects
				(font
					(size 1.27 1.27)
					(thickness 0.15)
				)
				(justify left bottom)
				(hide yes)
			)
		)
		(property "Description" ""
			(at 182.88 213.36 0)
			(effects
				(font
					(size 1.27 1.27)
				)
				(hide yes)
			)
		)
		(property "Author" "Antmicro"
			(at 198.12 215.9 0)
			(effects
				(font
					(size 1.27 1.27)
					(thickness 0.15)
				)
				(justify left bottom)
				(hide yes)
			)
		)
		(property "License" "Apache-2.0"
			(at 198.12 218.44 0)
			(effects
				(font
					(size 1.27 1.27)
					(thickness 0.15)
				)
				(justify left bottom)
				(hide yes)
			)
		)
		(pin "1"
		)
		(instances
			(project "data-center-rdimm-ddr5-tester"
				(path ""
					(reference "#PWR0176")
					(unit 1)
				)
			)
		)
	)
	(symbol
		(lib_id "antmicroTemperatureSensorsAnalogandDigitalOutput:TMP451AIDQFR")
		(at 88.9 224.79 0)
		(unit 1)
		(exclude_from_sim no)
		(in_bom yes)
		(on_board yes)
		(dnp no)
		(fields_autoplaced yes)
		(property "Reference" "U35"
			(at 97.79 217.805 0)
			(effects
				(font
					(size 1.27 1.27)
					(thickness 0.15)
				)
			)
		)
		(property "Value" "TMP451AIDQFR"
			(at 116.84 232.41 0)
			(effects
				(font
					(size 1.27 1.27)
					(thickness 0.15)
				)
				(justify left bottom)
				(hide yes)
			)
		)
		(property "Footprint" "antmicro-footprints:WSON-8_2x2mm"
			(at 116.84 234.95 0)
			(effects
				(font
					(size 1.27 1.27)
					(thickness 0.15)
				)
				(justify left bottom)
				(hide yes)
			)
		)
		(property "Datasheet" "https://www.ti.com/lit/ds/symlink/tmp451.pdf?ts=1727409102766"
			(at 116.84 237.49 0)
			(effects
				(font
					(size 1.27 1.27)
					(thickness 0.15)
				)
				(justify left bottom)
				(hide yes)
			)
		)
		(property "Description" ""
			(at 88.9 224.79 0)
			(effects
				(font
					(size 1.27 1.27)
				)
				(hide yes)
			)
		)
		(property "MPN" "TMP451AIDQFR"
			(at 97.79 220.345 0)
			(effects
				(font
					(size 1.27 1.27)
					(thickness 0.15)
				)
			)
		)
		(property "Manufacturer" "Texas Instruments"
			(at 116.84 229.87 0)
			(effects
				(font
					(size 1.27 1.27)
					(thickness 0.15)
				)
				(justify left bottom)
				(hide yes)
			)
		)
		(property "Author" "Antmicro"
			(at 116.84 240.03 0)
			(effects
				(font
					(size 1.27 1.27)
					(thickness 0.15)
				)
				(justify left bottom)
				(hide yes)
			)
		)
		(property "License" "Apache-2.0"
			(at 116.84 242.57 0)
			(effects
				(font
					(size 1.27 1.27)
					(thickness 0.15)
				)
				(justify left bottom)
				(hide yes)
			)
		)
		(pin "8"
		)
		(pin "2"
		)
		(pin "1"
		)
		(pin "7"
		)
		(pin "4"
		)
		(pin "5"
		)
		(pin "6"
		)
		(pin "3"
		)
		(instances
			(project "data-center-rdimm-ddr5-tester"
				(path ""
					(reference "U35")
					(unit 1)
				)
			)
		)
	)
	(symbol
		(lib_id "antmicroFPGAChips:XCAU25P-2FFVB676I")
		(at 81.28 53.34 0)
		(unit 1)
		(exclude_from_sim no)
		(in_bom yes)
		(on_board yes)
		(dnp no)
		(property "Reference" "U34"
			(at 86.36 45.72 0)
			(effects
				(font
					(size 1.27 1.27)
					(thickness 0.15)
				)
				(justify left)
			)
		)
		(property "Value" "XCAU25P-2FFVB676I"
			(at 144.78 58.42 0)
			(effects
				(font
					(size 1.27 1.27)
					(thickness 0.15)
				)
				(justify left bottom)
				(hide yes)
			)
		)
		(property "Footprint" "antmicro-footprints:BGA-676_27x27mm_Layout26x26_P1x1mm_FFVB676"
			(at 144.78 60.96 0)
			(effects
				(font
					(size 1.27 1.27)
					(thickness 0.15)
				)
				(justify left bottom)
				(hide yes)
			)
		)
		(property "Datasheet" "https://docs.xilinx.com/viewer/book-attachment/2PXOpPtpaABIt0fkzeBLnw/hvbsEUaOT0OxFhln7VEVyA"
			(at 144.78 63.5 0)
			(effects
				(font
					(size 1.27 1.27)
					(thickness 0.15)
				)
				(justify left bottom)
				(hide yes)
			)
		)
		(property "Description" ""
			(at 81.28 53.34 0)
			(effects
				(font
					(size 1.27 1.27)
				)
				(hide yes)
			)
		)
		(property "MPN" "XCAU25P-2FFVB676I"
			(at 86.36 48.26 0)
			(effects
				(font
					(size 1.27 1.27)
					(thickness 0.15)
				)
				(justify left)
			)
		)
		(property "Manufacturer" "AMD-Xilinx"
			(at 144.78 66.04 0)
			(effects
				(font
					(size 1.27 1.27)
					(thickness 0.15)
				)
				(justify left bottom)
				(hide yes)
			)
		)
		(property "Author" "Antmicro"
			(at 144.78 68.58 0)
			(effects
				(font
					(size 1.27 1.27)
					(thickness 0.15)
				)
				(justify left bottom)
				(hide yes)
			)
		)
		(property "License" "Apache-2.0"
			(at 144.78 71.12 0)
			(effects
				(font
					(size 1.27 1.27)
					(thickness 0.15)
				)
				(justify left bottom)
				(hide yes)
			)
		)
		(pin "AC23"
		)
		(pin "P20"
		)
		(pin "N19"
		)
		(pin "AA24"
		)
		(pin "J16"
		)
		(pin "J21"
		)
		(pin "AE10"
		)
		(pin "F6"
		)
		(pin "F7"
		)
		(pin "AF17"
		)
		(pin "AA15"
		)
		(pin "J25"
		)
		(pin "Y21"
		)
		(pin "AA7"
		)
		(pin "E26"
		)
		(pin "AD16"
		)
		(pin "V1"
		)
		(pin "AB14"
		)
		(pin "Y1"
		)
		(pin "E24"
		)
		(pin "AA14"
		)
		(pin "J20"
		)
		(pin "U25"
		)
		(pin "AE18"
		)
		(pin "U22"
		)
		(pin "P4"
		)
		(pin "P5"
		)
		(pin "R1"
		)
		(pin "R10"
		)
		(pin "P8"
		)
		(pin "P9"
		)
		(pin "R11"
		)
		(pin "R12"
		)
		(pin "AD3"
		)
		(pin "AD9"
		)
		(pin "AD4"
		)
		(pin "P18"
		)
		(pin "P3"
		)
		(pin "G14"
		)
		(pin "AE26"
		)
		(pin "B12"
		)
		(pin "AC2"
		)
		(pin "W7"
		)
		(pin "W8"
		)
		(pin "W11"
		)
		(pin "W17"
		)
		(pin "W2"
		)
		(pin "W22"
		)
		(pin "W3"
		)
		(pin "W6"
		)
		(pin "P6"
		)
		(pin "U26"
		)
		(pin "P19"
		)
		(pin "U1"
		)
		(pin "U10"
		)
		(pin "J15"
		)
		(pin "AB25"
		)
		(pin "L23"
		)
		(pin "P24"
		)
		(pin "G16"
		)
		(pin "C10"
		)
		(pin "F14"
		)
		(pin "U24"
		)
		(pin "Y24"
		)
		(pin "Y11"
		)
		(pin "J26"
		)
		(pin "AB4"
		)
		(pin "AD18"
		)
		(pin "J24"
		)
		(pin "AF2"
		)
		(pin "B26"
		)
		(pin "U6"
		)
		(pin "U7"
		)
		(pin "M11"
		)
		(pin "M12"
		)
		(pin "T20"
		)
		(pin "V23"
		)
		(pin "AD10"
		)
		(pin "D1"
		)
		(pin "AF1"
		)
		(pin "C8"
		)
		(pin "U13"
		)
		(pin "U14"
		)
		(pin "AD19"
		)
		(pin "Y4"
		)
		(pin "Y5"
		)
		(pin "E23"
		)
		(pin "C6"
		)
		(pin "AE14"
		)
		(pin "D22"
		)
		(pin "C20"
		)
		(pin "AB17"
		)
		(pin "AD24"
		)
		(pin "L1"
		)
		(pin "L10"
		)
		(pin "AE3"
		)
		(pin "G21"
		)
		(pin "AA17"
		)
		(pin "D6"
		)
		(pin "M25"
		)
		(pin "R17"
		)
		(pin "R18"
		)
		(pin "AE15"
		)
		(pin "H7"
		)
		(pin "H8"
		)
		(pin "R6"
		)
		(pin "R7"
		)
		(pin "AB20"
		)
		(pin "C5"
		)
		(pin "Y14"
		)
		(pin "AE13"
		)
		(pin "C13"
		)
		(pin "W4"
		)
		(pin "P22"
		)
		(pin "AF6"
		)
		(pin "B8"
		)
		(pin "AF18"
		)
		(pin "G22"
		)
		(pin "J2"
		)
		(pin "J3"
		)
		(pin "L3"
		)
		(pin "L6"
		)
		(pin "P12"
		)
		(pin "P15"
		)
		(pin "Y12"
		)
		(pin "K18"
		)
		(pin "V10"
		)
		(pin "V11"
		)
		(pin "D7"
		)
		(pin "D8"
		)
		(pin "P23"
		)
		(pin "AA3"
		)
		(pin "AB18"
		)
		(pin "H18"
		)
		(pin "B6"
		)
		(pin "R24"
		)
		(pin "R3"
		)
		(pin "P16"
		)
		(pin "P17"
		)
		(pin "AF23"
		)
		(pin "AC14"
		)
		(pin "M6"
		)
		(pin "B18"
		)
		(pin "M1"
		)
		(pin "B5"
		)
		(pin "D2"
		)
		(pin "G20"
		)
		(pin "M2"
		)
		(pin "B4"
		)
		(pin "AA16"
		)
		(pin "V9"
		)
		(pin "W1"
		)
		(pin "N5"
		)
		(pin "AA26"
		)
		(pin "B3"
		)
		(pin "D12"
		)
		(pin "N4"
		)
		(pin "AA2"
		)
		(pin "B23"
		)
		(pin "C12"
		)
		(pin "L5"
		)
		(pin "AA6"
		)
		(pin "B1"
		)
		(pin "H1"
		)
		(pin "A14"
		)
		(pin "A13"
		)
		(pin "AB2"
		)
		(pin "AE4"
		)
		(pin "Y16"
		)
		(pin "B24"
		)
		(pin "H16"
		)
		(pin "W24"
		)
		(pin "D18"
		)
		(pin "B20"
		)
		(pin "D21"
		)
		(pin "B19"
		)
		(pin "B25"
		)
		(pin "C24"
		)
		(pin "A15"
		)
		(pin "M26"
		)
		(pin "A23"
		)
		(pin "C17"
		)
		(pin "K21"
		)
		(pin "W23"
		)
		(pin "L24"
		)
		(pin "R20"
		)
		(pin "C21"
		)
		(pin "D24"
		)
		(pin "E15"
		)
		(pin "AD12"
		)
		(pin "D23"
		)
		(pin "D25"
		)
		(pin "C26"
		)
		(pin "B21"
		)
		(pin "Y26"
		)
		(pin "AE25"
		)
		(pin "C19"
		)
		(pin "C23"
		)
		(pin "P21"
		)
		(pin "A20"
		)
		(pin "L18"
		)
		(pin "A25"
		)
		(pin "K23"
		)
		(pin "V18"
		)
		(pin "C16"
		)
		(pin "V21"
		)
		(pin "E17"
		)
		(pin "A17"
		)
		(pin "P25"
		)
		(pin "AD25"
		)
		(pin "G18"
		)
		(pin "AB3"
		)
		(pin "J6"
		)
		(pin "J7"
		)
		(pin "K12"
		)
		(pin "K13"
		)
		(pin "AB16"
		)
		(pin "C1"
		)
		(pin "AF15"
		)
		(pin "J8"
		)
		(pin "K11"
		)
		(pin "AD1"
		)
		(pin "F25"
		)
		(pin "AE1"
		)
		(pin "V2"
		)
		(pin "U2"
		)
		(pin "U3"
		)
		(pin "F2"
		)
		(pin "V6"
		)
		(pin "P1"
		)
		(pin "L13"
		)
		(pin "L14"
		)
		(pin "AD5"
		)
		(pin "AE8"
		)
		(pin "AB10"
		)
		(pin "U15"
		)
		(pin "U16"
		)
		(pin "U17"
		)
		(pin "U18"
		)
		(pin "D26"
		)
		(pin "G5"
		)
		(pin "E25"
		)
		(pin "AD22"
		)
		(pin "A19"
		)
		(pin "P7"
		)
		(pin "Y2"
		)
		(pin "J22"
		)
		(pin "Y19"
		)
		(pin "Y3"
		)
		(pin "AB7"
		)
		(pin "AF22"
		)
		(pin "B2"
		)
		(pin "AA10"
		)
		(pin "V7"
		)
		(pin "V22"
		)
		(pin "J23"
		)
		(pin "AF12"
		)
		(pin "V16"
		)
		(pin "V17"
		)
		(pin "Y7"
		)
		(pin "D15"
		)
		(pin "H12"
		)
		(pin "AF7"
		)
		(pin "U23"
		)
		(pin "V19"
		)
		(pin "AF14"
		)
		(pin "AF13"
		)
		(pin "G8"
		)
		(pin "H20"
		)
		(pin "U11"
		)
		(pin "U12"
		)
		(pin "A5"
		)
		(pin "G6"
		)
		(pin "G7"
		)
		(pin "L15"
		)
		(pin "L16"
		)
		(pin "T8"
		)
		(pin "T9"
		)
		(pin "G19"
		)
		(pin "G17"
		)
		(pin "T4"
		)
		(pin "T5"
		)
		(pin "B13"
		)
		(pin "G23"
		)
		(pin "G3"
		)
		(pin "T26"
		)
		(pin "T3"
		)
		(pin "G13"
		)
		(pin "G2"
		)
		(pin "D17"
		)
		(pin "AD15"
		)
		(pin "Y8"
		)
		(pin "Y9"
		)
		(pin "AC24"
		)
		(pin "AD8"
		)
		(pin "F8"
		)
		(pin "G1"
		)
		(pin "AD6"
		)
		(pin "F18"
		)
		(pin "H17"
		)
		(pin "AA13"
		)
		(pin "K20"
		)
		(pin "AD7"
		)
		(pin "AA1"
		)
		(pin "AF19"
		)
		(pin "Y15"
		)
		(pin "AB13"
		)
		(pin "N13"
		)
		(pin "N14"
		)
		(pin "V14"
		)
		(pin "V15"
		)
		(pin "U8"
		)
		(pin "U9"
		)
		(pin "W13"
		)
		(pin "V5"
		)
		(pin "V8"
		)
		(pin "W5"
		)
		(pin "P26"
		)
		(pin "Y20"
		)
		(pin "L17"
		)
		(pin "L2"
		)
		(pin "H26"
		)
		(pin "Y6"
		)
		(pin "AC22"
		)
		(pin "D13"
		)
		(pin "V12"
		)
		(pin "V13"
		)
		(pin "AE9"
		)
		(pin "B7"
		)
		(pin "A11"
		)
		(pin "K9"
		)
		(pin "L11"
		)
		(pin "L12"
		)
		(pin "H5"
		)
		(pin "H6"
		)
		(pin "AE19"
		)
		(pin "C18"
		)
		(pin "H13"
		)
		(pin "AB23"
		)
		(pin "AC26"
		)
		(pin "R19"
		)
		(pin "R2"
		)
		(pin "H19"
		)
		(pin "AF20"
		)
		(pin "AF24"
		)
		(pin "B22"
		)
		(pin "B14"
		)
		(pin "D4"
		)
		(pin "AA18"
		)
		(pin "C22"
		)
		(pin "V24"
		)
		(pin "A12"
		)
		(pin "C7"
		)
		(pin "M7"
		)
		(pin "AB5"
		)
		(pin "W18"
		)
		(pin "T18"
		)
		(pin "T21"
		)
		(pin "F13"
		)
		(pin "D3"
		)
		(pin "F1"
		)
		(pin "L21"
		)
		(pin "L26"
		)
		(pin "AA11"
		)
		(pin "M20"
		)
		(pin "AC4"
		)
		(pin "AE5"
		)
		(pin "D19"
		)
		(pin "E10"
		)
		(pin "AA9"
		)
		(pin "Y22"
		)
		(pin "V3"
		)
		(pin "V4"
		)
		(pin "AD2"
		)
		(pin "AC10"
		)
		(pin "C25"
		)
		(pin "G4"
		)
		(pin "A6"
		)
		(pin "E6"
		)
		(pin "E7"
		)
		(pin "E1"
		)
		(pin "E19"
		)
		(pin "R4"
		)
		(pin "T10"
		)
		(pin "T11"
		)
		(pin "J10"
		)
		(pin "F17"
		)
		(pin "A24"
		)
		(pin "AC15"
		)
		(pin "C15"
		)
		(pin "A1"
		)
		(pin "J1"
		)
		(pin "J17"
		)
		(pin "AE6"
		)
		(pin "E4"
		)
		(pin "E5"
		)
		(pin "M23"
		)
		(pin "M3"
		)
		(pin "R22"
		)
		(pin "AA5"
		)
		(pin "AC12"
		)
		(pin "Y18"
		)
		(pin "W20"
		)
		(pin "AC21"
		)
		(pin "R23"
		)
		(pin "K10"
		)
		(pin "AC17"
		)
		(pin "AC20"
		)
		(pin "V20"
		)
		(pin "V25"
		)
		(pin "N1"
		)
		(pin "N10"
		)
		(pin "M4"
		)
		(pin "M5"
		)
		(pin "R25"
		)
		(pin "H3"
		)
		(pin "H4"
		)
		(pin "AD13"
		)
		(pin "AD17"
		)
		(pin "N26"
		)
		(pin "R13"
		)
		(pin "N6"
		)
		(pin "N7"
		)
		(pin "U4"
		)
		(pin "R5"
		)
		(pin "K3"
		)
		(pin "K4"
		)
		(pin "AF3"
		)
		(pin "J5"
		)
		(pin "P2"
		)
		(pin "N22"
		)
		(pin "T16"
		)
		(pin "T17"
		)
		(pin "C3"
		)
		(pin "AF4"
		)
		(pin "T13"
		)
		(pin "AA12"
		)
		(pin "AB26"
		)
		(pin "AF21"
		)
		(pin "N25"
		)
		(pin "N3"
		)
		(pin "N21"
		)
		(pin "J12"
		)
		(pin "A8"
		)
		(pin "W12"
		)
		(pin "H14"
		)
		(pin "U21"
		)
		(pin "W9"
		)
		(pin "T14"
		)
		(pin "AE23"
		)
		(pin "K19"
		)
		(pin "K24"
		)
		(pin "Y25"
		)
		(pin "G12"
		)
		(pin "N2"
		)
		(pin "N20"
		)
		(pin "T25"
		)
		(pin "AC8"
		)
		(pin "E16"
		)
		(pin "AC19"
		)
		(pin "C14"
		)
		(pin "F4"
		)
		(pin "F5"
		)
		(pin "U19"
		)
		(pin "AE12"
		)
		(pin "P14"
		)
		(pin "AF8"
		)
		(pin "AF9"
		)
		(pin "V26"
		)
		(pin "W19"
		)
		(pin "L4"
		)
		(pin "G24"
		)
		(pin "R15"
		)
		(pin "R16"
		)
		(pin "U5"
		)
		(pin "AC16"
		)
		(pin "AF25"
		)
		(pin "T7"
		)
		(pin "F24"
		)
		(pin "D16"
		)
		(pin "AA19"
		)
		(pin "D5"
		)
		(pin "L22"
		)
		(pin "B17"
		)
		(pin "H15"
		)
		(pin "AE21"
		)
		(pin "AE7"
		)
		(pin "K5"
		)
		(pin "K6"
		)
		(pin "T1"
		)
		(pin "AE22"
		)
		(pin "E22"
		)
		(pin "AF10"
		)
		(pin "AB6"
		)
		(pin "AD26"
		)
		(pin "AC13"
		)
		(pin "E18"
		)
		(pin "M15"
		)
		(pin "M16"
		)
		(pin "G15"
		)
		(pin "N8"
		)
		(pin "N9"
		)
		(pin "W26"
		)
		(pin "F20"
		)
		(pin "AD23"
		)
		(pin "AA8"
		)
		(pin "D20"
		)
		(pin "AF11"
		)
		(pin "E8"
		)
		(pin "F11"
		)
		(pin "AC5"
		)
		(pin "AA22"
		)
		(pin "E20"
		)
		(pin "W14"
		)
		(pin "M19"
		)
		(pin "H24"
		)
		(pin "K7"
		)
		(pin "K8"
		)
		(pin "C4"
		)
		(pin "H25"
		)
		(pin "W21"
		)
		(pin "P13"
		)
		(pin "L20"
		)
		(pin "AB21"
		)
		(pin "C2"
		)
		(pin "H22"
		)
		(pin "Y17"
		)
		(pin "AE11"
		)
		(pin "H2"
		)
		(pin "F23"
		)
		(pin "E11"
		)
		(pin "AB24"
		)
		(pin "AA4"
		)
		(pin "T6"
		)
		(pin "AD20"
		)
		(pin "A10"
		)
		(pin "C9"
		)
		(pin "W15"
		)
		(pin "E21"
		)
		(pin "AB22"
		)
		(pin "W16"
		)
		(pin "AC25"
		)
		(pin "T22"
		)
		(pin "K1"
		)
		(pin "AD14"
		)
		(pin "T2"
		)
		(pin "J19"
		)
		(pin "D9"
		)
		(pin "AE17"
		)
		(pin "AB1"
		)
		(pin "T24"
		)
		(pin "F9"
		)
		(pin "M8"
		)
		(pin "M9"
		)
		(pin "Y23"
		)
		(pin "AC7"
		)
		(pin "M13"
		)
		(pin "M14"
		)
		(pin "G25"
		)
		(pin "A9"
		)
		(pin "AB19"
		)
		(pin "A7"
		)
		(pin "N15"
		)
		(pin "N16"
		)
		(pin "Y13"
		)
		(pin "AF5"
		)
		(pin "R14"
		)
		(pin "AE20"
		)
		(pin "AB11"
		)
		(pin "W25"
		)
		(pin "T19"
		)
		(pin "H21"
		)
		(pin "K2"
		)
		(pin "T23"
		)
		(pin "AC6"
		)
		(pin "B15"
		)
		(pin "E9"
		)
		(pin "AC3"
		)
		(pin "F10"
		)
		(pin "A3"
		)
		(pin "F15"
		)
		(pin "U20"
		)
		(pin "G10"
		)
		(pin "N23"
		)
		(pin "AB15"
		)
		(pin "AA21"
		)
		(pin "P10"
		)
		(pin "P11"
		)
		(pin "J11"
		)
		(pin "Y10"
		)
		(pin "F19"
		)
		(pin "A22"
		)
		(pin "AE16"
		)
		(pin "F22"
		)
		(pin "G11"
		)
		(pin "K25"
		)
		(pin "B10"
		)
		(pin "AA20"
		)
		(pin "N24"
		)
		(pin "AA25"
		)
		(pin "E12"
		)
		(pin "D11"
		)
		(pin "E14"
		)
		(pin "AC1"
		)
		(pin "J4"
		)
		(pin "H11"
		)
		(pin "H9"
		)
		(pin "M22"
		)
		(pin "H10"
		)
		(pin "E13"
		)
		(pin "AD21"
		)
		(pin "D10"
		)
		(pin "B11"
		)
		(pin "G26"
		)
		(pin "L25"
		)
		(pin "AB9"
		)
		(pin "A2"
		)
		(pin "M21"
		)
		(pin "C11"
		)
		(pin "R21"
		)
		(pin "D14"
		)
		(pin "F12"
		)
		(pin "B9"
		)
		(pin "J9"
		)
		(pin "L19"
		)
		(pin "B16"
		)
		(pin "K22"
		)
		(pin "K26"
		)
		(pin "N11"
		)
		(pin "N12"
		)
		(pin "A16"
		)
		(pin "AB12"
		)
		(pin "L7"
		)
		(pin "L8"
		)
		(pin "AC11"
		)
		(pin "J18"
		)
		(pin "K16"
		)
		(pin "K17"
		)
		(pin "M24"
		)
		(pin "M17"
		)
		(pin "M18"
		)
		(pin "J14"
		)
		(pin "R8"
		)
		(pin "R9"
		)
		(pin "A26"
		)
		(pin "H23"
		)
		(pin "AF16"
		)
		(pin "F26"
		)
		(pin "F3"
		)
		(pin "AC18"
		)
		(pin "W10"
		)
		(pin "G9"
		)
		(pin "K14"
		)
		(pin "K15"
		)
		(pin "N17"
		)
		(pin "N18"
		)
		(pin "AC9"
		)
		(pin "J13"
		)
		(pin "AE24"
		)
		(pin "AA23"
		)
		(pin "E2"
		)
		(pin "E3"
		)
		(pin "AE2"
		)
		(pin "AF26"
		)
		(pin "A21"
		)
		(pin "L9"
		)
		(pin "M10"
		)
		(pin "F16"
		)
		(pin "F21"
		)
		(pin "R26"
		)
		(pin "T12"
		)
		(pin "T15"
		)
		(pin "AB8"
		)
		(pin "A18"
		)
		(pin "A4"
		)
		(pin "AD11"
		)
		(instances
			(project "data-center-rdimm-ddr5-tester"
				(path ""
					(reference "U34")
					(unit 1)
				)
			)
		)
	)
	(symbol
		(lib_id "antmicropower:+1V8")
		(at 334.01 119.38 0)
		(unit 1)
		(exclude_from_sim no)
		(in_bom yes)
		(on_board yes)
		(dnp no)
		(fields_autoplaced yes)
		(property "Reference" "#PWR022"
			(at 349.25 121.92 0)
			(effects
				(font
					(size 1.27 1.27)
					(thickness 0.15)
				)
				(justify left bottom)
				(hide yes)
			)
		)
		(property "Value" "+1V8"
			(at 334.01 114.3 0)
			(effects
				(font
					(size 1.27 1.27)
					(thickness 0.15)
				)
			)
		)
		(property "Footprint" ""
			(at 349.25 127 0)
			(effects
				(font
					(size 1.27 1.27)
					(thickness 0.15)
				)
				(justify left bottom)
				(hide yes)
			)
		)
		(property "Datasheet" ""
			(at 349.25 129.54 0)
			(effects
				(font
					(size 1.27 1.27)
					(thickness 0.15)
				)
				(justify left bottom)
				(hide yes)
			)
		)
		(property "Description" ""
			(at 334.01 119.38 0)
			(effects
				(font
					(size 1.27 1.27)
				)
				(hide yes)
			)
		)
		(property "Author" "Antmicro"
			(at 349.25 124.46 0)
			(effects
				(font
					(size 1.27 1.27)
					(thickness 0.15)
				)
				(justify left bottom)
				(hide yes)
			)
		)
		(property "License" "Apache-2.0"
			(at 349.25 127 0)
			(effects
				(font
					(size 1.27 1.27)
					(thickness 0.15)
				)
				(justify left bottom)
				(hide yes)
			)
		)
		(pin "1"
		)
		(instances
			(project "data-center-rdimm-ddr5-tester"
				(path ""
					(reference "#PWR022")
					(unit 1)
				)
			)
		)
	)
	(symbol
		(lib_id "antmicroResistors0402:R_100R_0402")
		(at 334.01 138.43 270)
		(unit 1)
		(exclude_from_sim no)
		(in_bom no)
		(on_board yes)
		(dnp yes)
		(property "Reference" "R22"
			(at 336.55 139.7 90)
			(effects
				(font
					(size 1.27 1.27)
				)
				(justify left)
			)
		)
		(property "Value" "R_100R_0402"
			(at 321.31 158.75 0)
			(effects
				(font
					(size 1.27 1.27)
					(thickness 0.15)
				)
				(justify left bottom)
				(hide yes)
			)
		)
		(property "Footprint" "antmicro-footprints:R_0402_1005Metric_EIA"
			(at 318.77 158.75 0)
			(effects
				(font
					(size 1.27 1.27)
					(thickness 0.15)
				)
				(justify left bottom)
				(hide yes)
			)
		)
		(property "Datasheet" "https://www.bourns.com/docs/product-datasheets/cr.pdf"
			(at 316.23 158.75 0)
			(effects
				(font
					(size 1.27 1.27)
					(thickness 0.15)
				)
				(justify left bottom)
				(hide yes)
			)
		)
		(property "Description" ""
			(at 334.01 138.43 0)
			(effects
				(font
					(size 1.27 1.27)
				)
				(hide yes)
			)
		)
		(property "Manufacturer" "Bourns"
			(at 311.15 158.75 0)
			(effects
				(font
					(size 1.27 1.27)
					(thickness 0.15)
				)
				(justify left bottom)
				(hide yes)
			)
		)
		(property "MPN" "CR0402-FX-1000GLF"
			(at 313.69 158.75 0)
			(effects
				(font
					(size 1.27 1.27)
					(thickness 0.15)
				)
				(justify left bottom)
				(hide yes)
			)
		)
		(property "Val" "100R"
			(at 336.55 142.8749 90)
			(effects
				(font
					(size 1.27 1.27)
					(thickness 0.15)
				)
				(justify left)
			)
		)
		(property "License" "Apache-2.0"
			(at 308.61 158.75 0)
			(effects
				(font
					(size 1.27 1.27)
					(thickness 0.15)
				)
				(justify left bottom)
				(hide yes)
			)
		)
		(property "Author" "Antmicro"
			(at 306.07 158.75 0)
			(effects
				(font
					(size 1.27 1.27)
					(thickness 0.15)
				)
				(justify left bottom)
				(hide yes)
			)
		)
		(property "Tolerance" "1%"
			(at 323.85 158.75 0)
			(effects
				(font
					(size 1.27 1.27)
				)
				(justify left bottom)
				(hide yes)
			)
		)
		(pin "1"
		)
		(pin "2"
		)
		(instances
			(project "data-center-rdimm-ddr5-tester"
				(path ""
					(reference "R22")
					(unit 1)
				)
			)
		)
	)
	(symbol
		(lib_id "antmicropower:+1V8")
		(at 213.36 114.3 0)
		(unit 1)
		(exclude_from_sim no)
		(in_bom yes)
		(on_board yes)
		(dnp no)
		(fields_autoplaced yes)
		(property "Reference" "#PWR020"
			(at 228.6 116.84 0)
			(effects
				(font
					(size 1.27 1.27)
					(thickness 0.15)
				)
				(justify left bottom)
				(hide yes)
			)
		)
		(property "Value" "+1V8"
			(at 213.36 109.22 0)
			(effects
				(font
					(size 1.27 1.27)
					(thickness 0.15)
				)
			)
		)
		(property "Footprint" ""
			(at 228.6 121.92 0)
			(effects
				(font
					(size 1.27 1.27)
					(thickness 0.15)
				)
				(justify left bottom)
				(hide yes)
			)
		)
		(property "Datasheet" ""
			(at 228.6 124.46 0)
			(effects
				(font
					(size 1.27 1.27)
					(thickness 0.15)
				)
				(justify left bottom)
				(hide yes)
			)
		)
		(property "Description" ""
			(at 213.36 114.3 0)
			(effects
				(font
					(size 1.27 1.27)
				)
				(hide yes)
			)
		)
		(property "Author" "Antmicro"
			(at 228.6 119.38 0)
			(effects
				(font
					(size 1.27 1.27)
					(thickness 0.15)
				)
				(justify left bottom)
				(hide yes)
			)
		)
		(property "License" "Apache-2.0"
			(at 228.6 121.92 0)
			(effects
				(font
					(size 1.27 1.27)
					(thickness 0.15)
				)
				(justify left bottom)
				(hide yes)
			)
		)
		(pin "1"
		)
		(instances
			(project "data-center-rdimm-ddr5-tester"
				(path ""
					(reference "#PWR020")
					(unit 1)
				)
			)
		)
	)
	(symbol
		(lib_id "antmicroCapacitors0402:C_100n_0402")
		(at 69.85 120.65 90)
		(unit 1)
		(exclude_from_sim no)
		(in_bom yes)
		(on_board yes)
		(dnp no)
		(property "Reference" "C69"
			(at 71.12 116.205 90)
			(effects
				(font
					(size 1.27 1.27)
				)
				(justify right)
			)
		)
		(property "Value" "C_100n_0402"
			(at 80.01 100.33 0)
			(effects
				(font
					(size 1.27 1.27)
					(thickness 0.15)
				)
				(justify left bottom)
				(hide yes)
			)
		)
		(property "Footprint" "antmicro-footprints:C_0402_1005Metric_EIA"
			(at 82.55 100.33 0)
			(effects
				(font
					(size 1.27 1.27)
					(thickness 0.15)
				)
				(justify left bottom)
				(hide yes)
			)
		)
		(property "Datasheet" "https://www.murata.com/products/productdetail?partno=GRM155R61H104KE14%23"
			(at 85.09 100.33 0)
			(effects
				(font
					(size 1.27 1.27)
					(thickness 0.15)
				)
				(justify left bottom)
				(hide yes)
			)
		)
		(property "Description" ""
			(at 69.85 120.65 0)
			(effects
				(font
					(size 1.27 1.27)
				)
				(hide yes)
			)
		)
		(property "Manufacturer" "Murata"
			(at 90.17 100.33 0)
			(effects
				(font
					(size 1.27 1.27)
					(thickness 0.15)
				)
				(justify left bottom)
				(hide yes)
			)
		)
		(property "MPN" "GRM155R61H104KE14D"
			(at 87.63 100.33 0)
			(effects
				(font
					(size 1.27 1.27)
					(thickness 0.15)
				)
				(justify left bottom)
				(hide yes)
			)
		)
		(property "Val" "100n"
			(at 71.12 120.015 90)
			(effects
				(font
					(size 1.27 1.27)
					(thickness 0.15)
				)
				(justify right)
			)
		)
		(property "License" "Apache-2.0"
			(at 92.71 100.33 0)
			(effects
				(font
					(size 1.27 1.27)
					(thickness 0.15)
				)
				(justify left bottom)
				(hide yes)
			)
		)
		(property "Author" "Antmicro"
			(at 95.25 100.33 0)
			(effects
				(font
					(size 1.27 1.27)
					(thickness 0.15)
				)
				(justify left bottom)
				(hide yes)
			)
		)
		(property "Voltage" "50V"
			(at 97.79 100.33 0)
			(effects
				(font
					(size 1.27 1.27)
				)
				(justify left bottom)
				(hide yes)
			)
		)
		(property "Dielectric" "X5R"
			(at 100.33 100.33 0)
			(effects
				(font
					(size 1.27 1.27)
				)
				(justify left bottom)
				(hide yes)
			)
		)
		(pin "1"
		)
		(pin "2"
		)
		(instances
			(project "data-center-rdimm-ddr5-tester"
				(path ""
					(reference "C69")
					(unit 1)
				)
			)
		)
	)
	(symbol
		(lib_id "antmicroPushbuttonSwitches:SW_KMR211NGLFS_SMD")
		(at 223.52 139.7 270)
		(unit 1)
		(exclude_from_sim no)
		(in_bom yes)
		(on_board yes)
		(dnp no)
		(fields_autoplaced yes)
		(property "Reference" "SW2"
			(at 227.076 143.9494 90)
			(effects
				(font
					(size 1.27 1.27)
					(thickness 0.15)
				)
				(justify left)
			)
		)
		(property "Value" "SW_KMR211NGLFS_SMD"
			(at 215.9 165.1 0)
			(effects
				(font
					(size 1.27 1.27)
					(thickness 0.15)
				)
				(justify left bottom)
				(hide yes)
			)
		)
		(property "Footprint" "antmicro-footprints:SW_KMR211NGLFS_SMD"
			(at 213.36 165.1 0)
			(effects
				(font
					(size 1.27 1.27)
					(thickness 0.15)
				)
				(justify left bottom)
				(hide yes)
			)
		)
		(property "Datasheet" "http://www.farnell.com/datasheets/2631211.pdf"
			(at 210.82 165.1 0)
			(effects
				(font
					(size 1.27 1.27)
					(thickness 0.15)
				)
				(justify left bottom)
				(hide yes)
			)
		)
		(property "Description" ""
			(at 223.52 139.7 0)
			(effects
				(font
					(size 1.27 1.27)
				)
				(hide yes)
			)
		)
		(property "MPN" "KMR211NGLFS"
			(at 227.076 146.4731 90)
			(effects
				(font
					(size 1.27 1.27)
					(thickness 0.15)
				)
				(justify left)
			)
		)
		(property "Manufacturer" "C&K"
			(at 208.28 165.1 0)
			(effects
				(font
					(size 1.27 1.27)
					(thickness 0.15)
				)
				(justify left bottom)
				(hide yes)
			)
		)
		(property "Author" "Antmicro"
			(at 205.74 165.1 0)
			(effects
				(font
					(size 1.27 1.27)
					(thickness 0.15)
				)
				(justify left bottom)
				(hide yes)
			)
		)
		(property "License" "Apache-2.0"
			(at 203.2 165.1 0)
			(effects
				(font
					(size 1.27 1.27)
					(thickness 0.15)
				)
				(justify left bottom)
				(hide yes)
			)
		)
		(pin "1"
		)
		(pin "2"
		)
		(pin "3"
		)
		(pin "4"
		)
		(instances
			(project "data-center-rdimm-ddr5-tester"
				(path ""
					(reference "SW2")
					(unit 1)
				)
			)
		)
	)
	(symbol
		(lib_id "antmicropower:GND")
		(at 195.58 58.42 0)
		(unit 1)
		(exclude_from_sim no)
		(in_bom yes)
		(on_board yes)
		(dnp no)
		(fields_autoplaced yes)
		(property "Reference" "#PWR0170"
			(at 195.58 64.77 0)
			(effects
				(font
					(size 1.27 1.27)
				)
				(hide yes)
			)
		)
		(property "Value" "GND"
			(at 193.675 62.865 0)
			(effects
				(font
					(size 1.27 1.27)
					(thickness 0.15)
				)
				(justify left bottom)
			)
		)
		(property "Footprint" ""
			(at 204.47 66.04 0)
			(effects
				(font
					(size 1.27 1.27)
					(thickness 0.15)
				)
				(justify left bottom)
				(hide yes)
			)
		)
		(property "Datasheet" ""
			(at 204.47 71.12 0)
			(effects
				(font
					(size 1.27 1.27)
					(thickness 0.15)
				)
				(justify left bottom)
				(hide yes)
			)
		)
		(property "Description" ""
			(at 195.58 58.42 0)
			(effects
				(font
					(size 1.27 1.27)
				)
				(hide yes)
			)
		)
		(property "Author" "Antmicro"
			(at 204.47 63.5 0)
			(effects
				(font
					(size 1.27 1.27)
					(thickness 0.15)
				)
				(justify left bottom)
				(hide yes)
			)
		)
		(property "License" "Apache-2.0"
			(at 204.47 66.04 0)
			(effects
				(font
					(size 1.27 1.27)
					(thickness 0.15)
				)
				(justify left bottom)
				(hide yes)
			)
		)
		(pin "1"
		)
		(instances
			(project "data-center-rdimm-ddr5-tester"
				(path ""
					(reference "#PWR0170")
					(unit 1)
				)
			)
		)
	)
	(symbol
		(lib_id "antmicroResistors0402:R_10k_0402")
		(at 354.33 217.17 270)
		(mirror x)
		(unit 1)
		(exclude_from_sim no)
		(in_bom yes)
		(on_board yes)
		(dnp no)
		(property "Reference" "R14"
			(at 353.06 213.995 90)
			(effects
				(font
					(size 1.27 1.27)
					(thickness 0.15)
				)
				(justify right)
			)
		)
		(property "Value" "R_10k_0402"
			(at 341.63 196.85 0)
			(effects
				(font
					(size 1.27 1.27)
					(thickness 0.15)
				)
				(justify left bottom)
				(hide yes)
			)
		)
		(property "Footprint" "antmicro-footprints:R_0402_1005Metric_EIA"
			(at 339.09 196.85 0)
			(effects
				(font
					(size 1.27 1.27)
					(thickness 0.15)
				)
				(justify left bottom)
				(hide yes)
			)
		)
		(property "Datasheet" "https://www.bourns.com/docs/product-datasheets/cr.pdf"
			(at 336.55 196.85 0)
			(effects
				(font
					(size 1.27 1.27)
					(thickness 0.15)
				)
				(justify left bottom)
				(hide yes)
			)
		)
		(property "Description" ""
			(at 354.33 217.17 0)
			(effects
				(font
					(size 1.27 1.27)
				)
				(hide yes)
			)
		)
		(property "MPN" "CR0402-FX-1002GLF"
			(at 334.01 196.85 0)
			(effects
				(font
					(size 1.27 1.27)
					(thickness 0.15)
				)
				(justify left bottom)
				(hide yes)
			)
		)
		(property "Manufacturer" "Bourns"
			(at 331.47 196.85 0)
			(effects
				(font
					(size 1.27 1.27)
					(thickness 0.15)
				)
				(justify left bottom)
				(hide yes)
			)
		)
		(property "License" "Apache-2.0"
			(at 328.93 196.85 0)
			(effects
				(font
					(size 1.27 1.27)
					(thickness 0.15)
				)
				(justify left bottom)
				(hide yes)
			)
		)
		(property "Author" "Antmicro"
			(at 326.39 196.85 0)
			(effects
				(font
					(size 1.27 1.27)
					(thickness 0.15)
				)
				(justify left bottom)
				(hide yes)
			)
		)
		(property "Val" "10k"
			(at 352.679 216.3231 90)
			(effects
				(font
					(size 1.27 1.27)
					(thickness 0.15)
				)
				(justify right)
			)
		)
		(property "Tolerance" "1%"
			(at 344.17 196.85 0)
			(effects
				(font
					(size 1.27 1.27)
				)
				(justify left bottom)
				(hide yes)
			)
		)
		(pin "1"
		)
		(pin "2"
		)
		(instances
			(project "data-center-rdimm-ddr5-tester"
				(path ""
					(reference "R14")
					(unit 1)
				)
			)
		)
	)
	(symbol
		(lib_id "antmicroTransistorsFETsMOSFETsSingle:BSS138PW")
		(at 260.35 238.76 0)
		(unit 1)
		(exclude_from_sim no)
		(in_bom yes)
		(on_board yes)
		(dnp no)
		(fields_autoplaced yes)
		(property "Reference" "Q3"
			(at 271.78 234.95 0)
			(effects
				(font
					(size 1.27 1.27)
					(thickness 0.15)
				)
				(justify left)
			)
		)
		(property "Value" "BSS138PW"
			(at 283.21 247.65 0)
			(effects
				(font
					(size 1.27 1.27)
					(thickness 0.15)
				)
				(justify left bottom)
				(hide yes)
			)
		)
		(property "Footprint" "antmicro-footprints:SC70-3"
			(at 283.21 250.19 0)
			(effects
				(font
					(size 1.27 1.27)
					(thickness 0.15)
				)
				(justify left bottom)
				(hide yes)
			)
		)
		(property "Datasheet" "https://assets.nexperia.com/documents/data-sheet/BSS138PW.pdf"
			(at 283.21 252.73 0)
			(effects
				(font
					(size 1.27 1.27)
					(thickness 0.15)
				)
				(justify left bottom)
				(hide yes)
			)
		)
		(property "Description" ""
			(at 260.35 238.76 0)
			(effects
				(font
					(size 1.27 1.27)
				)
				(hide yes)
			)
		)
		(property "MPN" "BSS138PW"
			(at 271.78 237.49 0)
			(effects
				(font
					(size 1.27 1.27)
					(thickness 0.15)
				)
				(justify left)
			)
		)
		(property "Manufacturer" "Nexperia"
			(at 283.21 257.81 0)
			(effects
				(font
					(size 1.27 1.27)
					(thickness 0.15)
				)
				(justify left bottom)
				(hide yes)
			)
		)
		(property "Author" "Antmicro"
			(at 283.21 260.35 0)
			(effects
				(font
					(size 1.27 1.27)
					(thickness 0.15)
				)
				(justify left bottom)
				(hide yes)
			)
		)
		(property "License" "Apache-2.0"
			(at 283.21 262.89 0)
			(effects
				(font
					(size 1.27 1.27)
					(thickness 0.15)
				)
				(justify left bottom)
				(hide yes)
			)
		)
		(pin "1"
		)
		(pin "3"
		)
		(pin "2"
		)
		(instances
			(project "data-center-rdimm-ddr5-tester"
				(path ""
					(reference "Q3")
					(unit 1)
				)
			)
		)
	)
	(symbol
		(lib_id "antmicropower:+1V8")
		(at 80.01 50.8 0)
		(unit 1)
		(exclude_from_sim no)
		(in_bom yes)
		(on_board yes)
		(dnp no)
		(fields_autoplaced yes)
		(property "Reference" "#PWR019"
			(at 95.25 53.34 0)
			(effects
				(font
					(size 1.27 1.27)
					(thickness 0.15)
				)
				(justify left bottom)
				(hide yes)
			)
		)
		(property "Value" "+1V8"
			(at 80.01 45.72 0)
			(effects
				(font
					(size 1.27 1.27)
					(thickness 0.15)
				)
			)
		)
		(property "Footprint" ""
			(at 95.25 58.42 0)
			(effects
				(font
					(size 1.27 1.27)
					(thickness 0.15)
				)
				(justify left bottom)
				(hide yes)
			)
		)
		(property "Datasheet" ""
			(at 95.25 60.96 0)
			(effects
				(font
					(size 1.27 1.27)
					(thickness 0.15)
				)
				(justify left bottom)
				(hide yes)
			)
		)
		(property "Description" ""
			(at 80.01 50.8 0)
			(effects
				(font
					(size 1.27 1.27)
				)
				(hide yes)
			)
		)
		(property "Author" "Antmicro"
			(at 95.25 55.88 0)
			(effects
				(font
					(size 1.27 1.27)
					(thickness 0.15)
				)
				(justify left bottom)
				(hide yes)
			)
		)
		(property "License" "Apache-2.0"
			(at 95.25 58.42 0)
			(effects
				(font
					(size 1.27 1.27)
					(thickness 0.15)
				)
				(justify left bottom)
				(hide yes)
			)
		)
		(pin "1"
		)
		(instances
			(project "data-center-rdimm-ddr5-tester"
				(path ""
					(reference "#PWR019")
					(unit 1)
				)
			)
		)
	)
	(symbol
		(lib_id "antmicropower:GND")
		(at 353.06 143.51 0)
		(unit 1)
		(exclude_from_sim no)
		(in_bom yes)
		(on_board yes)
		(dnp no)
		(fields_autoplaced yes)
		(property "Reference" "#PWR025"
			(at 353.06 149.86 0)
			(effects
				(font
					(size 1.27 1.27)
				)
				(hide yes)
			)
		)
		(property "Value" "GND"
			(at 351.155 147.955 0)
			(effects
				(font
					(size 1.27 1.27)
					(thickness 0.15)
				)
				(justify left bottom)
			)
		)
		(property "Footprint" ""
			(at 361.95 151.13 0)
			(effects
				(font
					(size 1.27 1.27)
					(thickness 0.15)
				)
				(justify left bottom)
				(hide yes)
			)
		)
		(property "Datasheet" ""
			(at 361.95 156.21 0)
			(effects
				(font
					(size 1.27 1.27)
					(thickness 0.15)
				)
				(justify left bottom)
				(hide yes)
			)
		)
		(property "Description" ""
			(at 353.06 143.51 0)
			(effects
				(font
					(size 1.27 1.27)
				)
				(hide yes)
			)
		)
		(property "Author" "Antmicro"
			(at 361.95 148.59 0)
			(effects
				(font
					(size 1.27 1.27)
					(thickness 0.15)
				)
				(justify left bottom)
				(hide yes)
			)
		)
		(property "License" "Apache-2.0"
			(at 361.95 151.13 0)
			(effects
				(font
					(size 1.27 1.27)
					(thickness 0.15)
				)
				(justify left bottom)
				(hide yes)
			)
		)
		(pin "1"
		)
		(instances
			(project "data-center-rdimm-ddr5-tester"
				(path ""
					(reference "#PWR025")
					(unit 1)
				)
			)
		)
	)
	(symbol
		(lib_id "antmicroTransistorsFETsMOSFETsSingle:BSS138PW")
		(at 217.17 238.76 0)
		(unit 1)
		(exclude_from_sim no)
		(in_bom yes)
		(on_board yes)
		(dnp no)
		(fields_autoplaced yes)
		(property "Reference" "Q2"
			(at 228.6 234.95 0)
			(effects
				(font
					(size 1.27 1.27)
					(thickness 0.15)
				)
				(justify left)
			)
		)
		(property "Value" "BSS138PW"
			(at 240.03 247.65 0)
			(effects
				(font
					(size 1.27 1.27)
					(thickness 0.15)
				)
				(justify left bottom)
				(hide yes)
			)
		)
		(property "Footprint" "antmicro-footprints:SC70-3"
			(at 240.03 250.19 0)
			(effects
				(font
					(size 1.27 1.27)
					(thickness 0.15)
				)
				(justify left bottom)
				(hide yes)
			)
		)
		(property "Datasheet" "https://assets.nexperia.com/documents/data-sheet/BSS138PW.pdf"
			(at 240.03 252.73 0)
			(effects
				(font
					(size 1.27 1.27)
					(thickness 0.15)
				)
				(justify left bottom)
				(hide yes)
			)
		)
		(property "Description" ""
			(at 217.17 238.76 0)
			(effects
				(font
					(size 1.27 1.27)
				)
				(hide yes)
			)
		)
		(property "MPN" "BSS138PW"
			(at 228.6 237.49 0)
			(effects
				(font
					(size 1.27 1.27)
					(thickness 0.15)
				)
				(justify left)
			)
		)
		(property "Manufacturer" "Nexperia"
			(at 240.03 257.81 0)
			(effects
				(font
					(size 1.27 1.27)
					(thickness 0.15)
				)
				(justify left bottom)
				(hide yes)
			)
		)
		(property "Author" "Antmicro"
			(at 240.03 260.35 0)
			(effects
				(font
					(size 1.27 1.27)
					(thickness 0.15)
				)
				(justify left bottom)
				(hide yes)
			)
		)
		(property "License" "Apache-2.0"
			(at 240.03 262.89 0)
			(effects
				(font
					(size 1.27 1.27)
					(thickness 0.15)
				)
				(justify left bottom)
				(hide yes)
			)
		)
		(pin "1"
		)
		(pin "3"
		)
		(pin "2"
		)
		(instances
			(project "data-center-rdimm-ddr5-tester"
				(path ""
					(reference "Q2")
					(unit 1)
				)
			)
		)
	)
	(symbol
		(lib_id "antmicropower:+3V3")
		(at 31.75 224.79 0)
		(unit 1)
		(exclude_from_sim no)
		(in_bom yes)
		(on_board yes)
		(dnp no)
		(fields_autoplaced yes)
		(property "Reference" "#PWR0332"
			(at 31.75 228.6 0)
			(effects
				(font
					(size 1.27 1.27)
				)
				(hide yes)
			)
		)
		(property "Value" "+3V3"
			(at 28.575 222.25 0)
			(effects
				(font
					(size 1.27 1.27)
					(thickness 0.15)
				)
				(justify left bottom)
			)
		)
		(property "Footprint" ""
			(at 46.99 232.41 0)
			(effects
				(font
					(size 1.27 1.27)
					(thickness 0.15)
				)
				(justify left bottom)
				(hide yes)
			)
		)
		(property "Datasheet" ""
			(at 46.99 234.95 0)
			(effects
				(font
					(size 1.27 1.27)
					(thickness 0.15)
				)
				(justify left bottom)
				(hide yes)
			)
		)
		(property "Description" ""
			(at 31.75 224.79 0)
			(effects
				(font
					(size 1.27 1.27)
				)
				(hide yes)
			)
		)
		(property "Author" "Antmicro"
			(at 46.99 227.33 0)
			(effects
				(font
					(size 1.27 1.27)
					(thickness 0.15)
				)
				(justify left bottom)
				(hide yes)
			)
		)
		(property "License" "Apache-2.0"
			(at 46.99 229.87 0)
			(effects
				(font
					(size 1.27 1.27)
					(thickness 0.15)
				)
				(justify left bottom)
				(hide yes)
			)
		)
		(pin "1"
		)
		(instances
			(project "data-center-rdimm-ddr5-tester"
				(path ""
					(reference "#PWR0332")
					(unit 1)
				)
			)
		)
	)
	(symbol
		(lib_id "antmicroCapacitors0402:C_100n_0402")
		(at 231.14 57.15 90)
		(unit 1)
		(exclude_from_sim no)
		(in_bom yes)
		(on_board yes)
		(dnp no)
		(fields_autoplaced yes)
		(property "Reference" "C205"
			(at 234.315 53.3336 90)
			(effects
				(font
					(size 1.27 1.27)
					(thickness 0.15)
				)
				(justify right)
			)
		)
		(property "Value" "C_100n_0402"
			(at 241.3 36.83 0)
			(effects
				(font
					(size 1.27 1.27)
					(thickness 0.15)
				)
				(justify left bottom)
				(hide yes)
			)
		)
		(property "Footprint" "antmicro-footprints:C_0402_1005Metric"
			(at 243.84 36.83 0)
			(effects
				(font
					(size 1.27 1.27)
					(thickness 0.15)
				)
				(justify left bottom)
				(hide yes)
			)
		)
		(property "Datasheet" "https://www.murata.com/products/productdetail?partno=GRM155R61H104KE14%23"
			(at 246.38 36.83 0)
			(effects
				(font
					(size 1.27 1.27)
					(thickness 0.15)
				)
				(justify left bottom)
				(hide yes)
			)
		)
		(property "Description" ""
			(at 231.14 57.15 0)
			(effects
				(font
					(size 1.27 1.27)
				)
				(hide yes)
			)
		)
		(property "MPN" "GRM155R61H104KE14D"
			(at 248.92 36.83 0)
			(effects
				(font
					(size 1.27 1.27)
					(thickness 0.15)
				)
				(justify left bottom)
				(hide yes)
			)
		)
		(property "Manufacturer" "Murata"
			(at 251.46 36.83 0)
			(effects
				(font
					(size 1.27 1.27)
					(thickness 0.15)
				)
				(justify left bottom)
				(hide yes)
			)
		)
		(property "License" "Apache-2.0"
			(at 254 36.83 0)
			(effects
				(font
					(size 1.27 1.27)
					(thickness 0.15)
				)
				(justify left bottom)
				(hide yes)
			)
		)
		(property "Author" "Antmicro"
			(at 256.54 36.83 0)
			(effects
				(font
					(size 1.27 1.27)
					(thickness 0.15)
				)
				(justify left bottom)
				(hide yes)
			)
		)
		(property "Val" "100n"
			(at 234.315 55.8736 90)
			(effects
				(font
					(size 1.27 1.27)
					(thickness 0.15)
				)
				(justify right)
			)
		)
		(property "Voltage" "50V"
			(at 259.08 36.83 0)
			(effects
				(font
					(size 1.27 1.27)
				)
				(justify left bottom)
				(hide yes)
			)
		)
		(property "Dielectric" "X5R"
			(at 261.62 36.83 0)
			(effects
				(font
					(size 1.27 1.27)
				)
				(justify left bottom)
				(hide yes)
			)
		)
		(pin "2"
		)
		(pin "1"
		)
		(instances
			(project "data-center-rdimm-ddr5-tester"
				(path ""
					(reference "C205")
					(unit 1)
				)
			)
		)
	)
	(symbol
		(lib_id "antmicropower:GND")
		(at 31.75 233.68 0)
		(unit 1)
		(exclude_from_sim no)
		(in_bom yes)
		(on_board yes)
		(dnp no)
		(property "Reference" "#PWR0331"
			(at 31.75 240.03 0)
			(effects
				(font
					(size 1.27 1.27)
				)
				(hide yes)
			)
		)
		(property "Value" "GND"
			(at 29.845 238.125 0)
			(effects
				(font
					(size 1.27 1.27)
					(thickness 0.15)
				)
				(justify left bottom)
			)
		)
		(property "Footprint" ""
			(at 40.64 241.3 0)
			(effects
				(font
					(size 1.27 1.27)
					(thickness 0.15)
				)
				(justify left bottom)
				(hide yes)
			)
		)
		(property "Datasheet" ""
			(at 40.64 246.38 0)
			(effects
				(font
					(size 1.27 1.27)
					(thickness 0.15)
				)
				(justify left bottom)
				(hide yes)
			)
		)
		(property "Description" ""
			(at 31.75 233.68 0)
			(effects
				(font
					(size 1.27 1.27)
				)
				(hide yes)
			)
		)
		(property "Author" "Antmicro"
			(at 40.64 238.76 0)
			(effects
				(font
					(size 1.27 1.27)
					(thickness 0.15)
				)
				(justify left bottom)
				(hide yes)
			)
		)
		(property "License" "Apache-2.0"
			(at 40.64 241.3 0)
			(effects
				(font
					(size 1.27 1.27)
					(thickness 0.15)
				)
				(justify left bottom)
				(hide yes)
			)
		)
		(pin "1"
		)
		(instances
			(project "data-center-rdimm-ddr5-tester"
				(path ""
					(reference "#PWR0331")
					(unit 1)
				)
			)
		)
	)
	(symbol
		(lib_id "antmicropower:GND")
		(at 182.88 243.84 0)
		(unit 1)
		(exclude_from_sim no)
		(in_bom yes)
		(on_board yes)
		(dnp no)
		(fields_autoplaced yes)
		(property "Reference" "#PWR0175"
			(at 182.88 250.19 0)
			(effects
				(font
					(size 1.27 1.27)
				)
				(hide yes)
			)
		)
		(property "Value" "GND"
			(at 180.975 248.285 0)
			(effects
				(font
					(size 1.27 1.27)
					(thickness 0.15)
				)
				(justify left bottom)
			)
		)
		(property "Footprint" ""
			(at 191.77 251.46 0)
			(effects
				(font
					(size 1.27 1.27)
					(thickness 0.15)
				)
				(justify left bottom)
				(hide yes)
			)
		)
		(property "Datasheet" ""
			(at 191.77 256.54 0)
			(effects
				(font
					(size 1.27 1.27)
					(thickness 0.15)
				)
				(justify left bottom)
				(hide yes)
			)
		)
		(property "Description" ""
			(at 182.88 243.84 0)
			(effects
				(font
					(size 1.27 1.27)
				)
				(hide yes)
			)
		)
		(property "Author" "Antmicro"
			(at 191.77 248.92 0)
			(effects
				(font
					(size 1.27 1.27)
					(thickness 0.15)
				)
				(justify left bottom)
				(hide yes)
			)
		)
		(property "License" "Apache-2.0"
			(at 191.77 251.46 0)
			(effects
				(font
					(size 1.27 1.27)
					(thickness 0.15)
				)
				(justify left bottom)
				(hide yes)
			)
		)
		(pin "1"
		)
		(instances
			(project "data-center-rdimm-ddr5-tester"
				(path ""
					(reference "#PWR0175")
					(unit 1)
				)
			)
		)
	)
	(symbol
		(lib_id "antmicroCapacitors0402:C_100n_0402")
		(at 31.75 232.41 90)
		(unit 1)
		(exclude_from_sim no)
		(in_bom yes)
		(on_board yes)
		(dnp no)
		(property "Reference" "C223"
			(at 33.02 227.965 90)
			(effects
				(font
					(size 1.27 1.27)
				)
				(justify right)
			)
		)
		(property "Value" "C_100n_0402"
			(at 41.91 212.09 0)
			(effects
				(font
					(size 1.27 1.27)
					(thickness 0.15)
				)
				(justify left bottom)
				(hide yes)
			)
		)
		(property "Footprint" "antmicro-footprints:C_0402_1005Metric"
			(at 44.45 212.09 0)
			(effects
				(font
					(size 1.27 1.27)
					(thickness 0.15)
				)
				(justify left bottom)
				(hide yes)
			)
		)
		(property "Datasheet" "https://www.murata.com/products/productdetail?partno=GRM155R61H104KE14%23"
			(at 46.99 212.09 0)
			(effects
				(font
					(size 1.27 1.27)
					(thickness 0.15)
				)
				(justify left bottom)
				(hide yes)
			)
		)
		(property "Description" ""
			(at 31.75 232.41 0)
			(effects
				(font
					(size 1.27 1.27)
				)
				(hide yes)
			)
		)
		(property "Manufacturer" "Murata"
			(at 52.07 212.09 0)
			(effects
				(font
					(size 1.27 1.27)
					(thickness 0.15)
				)
				(justify left bottom)
				(hide yes)
			)
		)
		(property "MPN" "GRM155R61H104KE14D"
			(at 49.53 212.09 0)
			(effects
				(font
					(size 1.27 1.27)
					(thickness 0.15)
				)
				(justify left bottom)
				(hide yes)
			)
		)
		(property "Val" "100n"
			(at 33.02 231.775 90)
			(effects
				(font
					(size 1.27 1.27)
					(thickness 0.15)
				)
				(justify right)
			)
		)
		(property "License" "Apache-2.0"
			(at 54.61 212.09 0)
			(effects
				(font
					(size 1.27 1.27)
					(thickness 0.15)
				)
				(justify left bottom)
				(hide yes)
			)
		)
		(property "Author" "Antmicro"
			(at 57.15 212.09 0)
			(effects
				(font
					(size 1.27 1.27)
					(thickness 0.15)
				)
				(justify left bottom)
				(hide yes)
			)
		)
		(property "Voltage" "50V"
			(at 59.69 212.09 0)
			(effects
				(font
					(size 1.27 1.27)
				)
				(justify left bottom)
				(hide yes)
			)
		)
		(property "Dielectric" "X5R"
			(at 62.23 212.09 0)
			(effects
				(font
					(size 1.27 1.27)
				)
				(justify left bottom)
				(hide yes)
			)
		)
		(pin "1"
		)
		(pin "2"
		)
		(instances
			(project "data-center-rdimm-ddr5-tester"
				(path ""
					(reference "C223")
					(unit 1)
				)
			)
		)
	)
	(symbol
		(lib_id "antmicroShuntsJumpers:Net-Tie_P0.127mm")
		(at 245.11 48.26 0)
		(unit 1)
		(exclude_from_sim no)
		(in_bom no)
		(on_board yes)
		(dnp no)
		(property "Reference" "TP3"
			(at 247.65 45.72 0)
			(effects
				(font
					(size 1.27 1.27)
					(thickness 0.15)
				)
			)
		)
		(property "Value" "Net-Tie_P0.127mm"
			(at 248.285 45.72 0)
			(effects
				(font
					(size 1.27 1.27)
					(thickness 0.15)
				)
				(hide yes)
			)
		)
		(property "Footprint" "antmicro-footprints:NetTie-2_SMD_Pad0.127mm"
			(at 266.7 60.96 0)
			(effects
				(font
					(size 1.27 1.27)
					(thickness 0.15)
				)
				(justify left bottom)
				(hide yes)
			)
		)
		(property "Datasheet" ""
			(at 266.7 63.5 0)
			(effects
				(font
					(size 1.27 1.27)
					(thickness 0.15)
				)
				(justify left bottom)
				(hide yes)
			)
		)
		(property "Description" ""
			(at 245.11 48.26 0)
			(effects
				(font
					(size 1.27 1.27)
				)
				(hide yes)
			)
		)
		(property "MPN" ""
			(at 266.7 58.42 0)
			(effects
				(font
					(size 1.27 1.27)
					(thickness 0.15)
				)
				(justify left bottom)
			)
		)
		(property "Manufacturer" ""
			(at 266.7 66.04 0)
			(effects
				(font
					(size 1.27 1.27)
					(thickness 0.15)
				)
				(justify left bottom)
				(hide yes)
			)
		)
		(property "Author" "Antmicro"
			(at 266.7 68.58 0)
			(effects
				(font
					(size 1.27 1.27)
					(thickness 0.15)
				)
				(justify left bottom)
				(hide yes)
			)
		)
		(property "License" "Apache-2.0"
			(at 266.7 71.12 0)
			(effects
				(font
					(size 1.27 1.27)
					(thickness 0.15)
				)
				(justify left bottom)
				(hide yes)
			)
		)
		(pin "2"
		)
		(pin "1"
		)
		(instances
			(project "data-center-rdimm-ddr5-tester"
				(path ""
					(reference "TP3")
					(unit 1)
				)
			)
		)
	)
	(symbol
		(lib_id "antmicroTransistorsFETsMOSFETsSingle:BSS138PW")
		(at 175.26 238.76 0)
		(unit 1)
		(exclude_from_sim no)
		(in_bom yes)
		(on_board yes)
		(dnp no)
		(fields_autoplaced yes)
		(property "Reference" "Q1"
			(at 186.69 234.95 0)
			(effects
				(font
					(size 1.27 1.27)
					(thickness 0.15)
				)
				(justify left)
			)
		)
		(property "Value" "BSS138PW"
			(at 198.12 247.65 0)
			(effects
				(font
					(size 1.27 1.27)
					(thickness 0.15)
				)
				(justify left bottom)
				(hide yes)
			)
		)
		(property "Footprint" "antmicro-footprints:SC70-3"
			(at 198.12 250.19 0)
			(effects
				(font
					(size 1.27 1.27)
					(thickness 0.15)
				)
				(justify left bottom)
				(hide yes)
			)
		)
		(property "Datasheet" "https://assets.nexperia.com/documents/data-sheet/BSS138PW.pdf"
			(at 198.12 252.73 0)
			(effects
				(font
					(size 1.27 1.27)
					(thickness 0.15)
				)
				(justify left bottom)
				(hide yes)
			)
		)
		(property "Description" ""
			(at 175.26 238.76 0)
			(effects
				(font
					(size 1.27 1.27)
				)
				(hide yes)
			)
		)
		(property "MPN" "BSS138PW"
			(at 186.69 237.49 0)
			(effects
				(font
					(size 1.27 1.27)
					(thickness 0.15)
				)
				(justify left)
			)
		)
		(property "Manufacturer" "Nexperia"
			(at 198.12 257.81 0)
			(effects
				(font
					(size 1.27 1.27)
					(thickness 0.15)
				)
				(justify left bottom)
				(hide yes)
			)
		)
		(property "Author" "Antmicro"
			(at 198.12 260.35 0)
			(effects
				(font
					(size 1.27 1.27)
					(thickness 0.15)
				)
				(justify left bottom)
				(hide yes)
			)
		)
		(property "License" "Apache-2.0"
			(at 198.12 262.89 0)
			(effects
				(font
					(size 1.27 1.27)
					(thickness 0.15)
				)
				(justify left bottom)
				(hide yes)
			)
		)
		(pin "1"
		)
		(pin "3"
		)
		(pin "2"
		)
		(instances
			(project "data-center-rdimm-ddr5-tester"
				(path ""
					(reference "Q1")
					(unit 1)
				)
			)
		)
	)
	(symbol
		(lib_id "antmicroTVSDiodes:PESD5V0X1UB")
		(at 208.28 140.97 90)
		(mirror x)
		(unit 1)
		(exclude_from_sim no)
		(in_bom yes)
		(on_board yes)
		(dnp no)
		(property "Reference" "D9"
			(at 203.2 142.24 90)
			(effects
				(font
					(size 1.27 1.27)
					(thickness 0.15)
				)
				(justify right)
			)
		)
		(property "Value" "PESD5V0X1UB"
			(at 213.36 156.21 0)
			(effects
				(font
					(size 1.27 1.27)
					(thickness 0.15)
				)
				(justify left bottom)
				(hide yes)
			)
		)
		(property "Footprint" "antmicro-footprints:SOD-523"
			(at 215.9 156.21 0)
			(effects
				(font
					(size 1.27 1.27)
					(thickness 0.15)
				)
				(justify left bottom)
				(hide yes)
			)
		)
		(property "Datasheet" "https://assets.nexperia.com/documents/data-sheet/PESD5V0X1UB.pdf"
			(at 218.44 156.21 0)
			(effects
				(font
					(size 1.27 1.27)
					(thickness 0.15)
				)
				(justify left bottom)
				(hide yes)
			)
		)
		(property "Description" ""
			(at 208.28 140.97 0)
			(effects
				(font
					(size 1.27 1.27)
				)
				(hide yes)
			)
		)
		(property "MPN" "PESD5V0X1UB,135"
			(at 187.96 144.78 90)
			(effects
				(font
					(size 1.27 1.27)
					(thickness 0.15)
				)
				(justify right)
			)
		)
		(property "Manufacturer" "Nexperia"
			(at 220.98 156.21 0)
			(effects
				(font
					(size 1.27 1.27)
					(thickness 0.15)
				)
				(justify left bottom)
				(hide yes)
			)
		)
		(property "Author" "Antmicro"
			(at 223.52 156.21 0)
			(effects
				(font
					(size 1.27 1.27)
					(thickness 0.15)
				)
				(justify left bottom)
				(hide yes)
			)
		)
		(property "License" "Apache-2.0"
			(at 226.06 156.21 0)
			(effects
				(font
					(size 1.27 1.27)
					(thickness 0.15)
				)
				(justify left bottom)
				(hide yes)
			)
		)
		(pin "1"
		)
		(pin "2"
		)
		(instances
			(project "data-center-rdimm-ddr5-tester"
				(path ""
					(reference "D9")
					(unit 1)
				)
			)
		)
	)
	(symbol
		(lib_id "antmicropower:GND")
		(at 205.74 53.34 0)
		(unit 1)
		(exclude_from_sim no)
		(in_bom yes)
		(on_board yes)
		(dnp no)
		(fields_autoplaced yes)
		(property "Reference" "#PWR0372"
			(at 205.74 59.69 0)
			(effects
				(font
					(size 1.27 1.27)
				)
				(hide yes)
			)
		)
		(property "Value" "GND"
			(at 203.835 57.785 0)
			(effects
				(font
					(size 1.27 1.27)
					(thickness 0.15)
				)
				(justify left bottom)
			)
		)
		(property "Footprint" ""
			(at 214.63 60.96 0)
			(effects
				(font
					(size 1.27 1.27)
					(thickness 0.15)
				)
				(justify left bottom)
				(hide yes)
			)
		)
		(property "Datasheet" ""
			(at 214.63 66.04 0)
			(effects
				(font
					(size 1.27 1.27)
					(thickness 0.15)
				)
				(justify left bottom)
				(hide yes)
			)
		)
		(property "Description" ""
			(at 205.74 53.34 0)
			(effects
				(font
					(size 1.27 1.27)
				)
				(hide yes)
			)
		)
		(property "Author" "Antmicro"
			(at 214.63 58.42 0)
			(effects
				(font
					(size 1.27 1.27)
					(thickness 0.15)
				)
				(justify left bottom)
				(hide yes)
			)
		)
		(property "License" "Apache-2.0"
			(at 214.63 60.96 0)
			(effects
				(font
					(size 1.27 1.27)
					(thickness 0.15)
				)
				(justify left bottom)
				(hide yes)
			)
		)
		(pin "1"
		)
		(instances
			(project "data-center-rdimm-ddr5-tester"
				(path ""
					(reference "#PWR0372")
					(unit 1)
				)
			)
		)
	)
	(symbol
		(lib_id "antmicropower:+3V3")
		(at 224.79 213.36 0)
		(unit 1)
		(exclude_from_sim no)
		(in_bom yes)
		(on_board yes)
		(dnp no)
		(fields_autoplaced yes)
		(property "Reference" "#PWR0178"
			(at 224.79 217.17 0)
			(effects
				(font
					(size 1.27 1.27)
				)
				(hide yes)
			)
		)
		(property "Value" "+3V3"
			(at 221.615 210.82 0)
			(effects
				(font
					(size 1.27 1.27)
					(thickness 0.15)
				)
				(justify left bottom)
			)
		)
		(property "Footprint" ""
			(at 240.03 220.98 0)
			(effects
				(font
					(size 1.27 1.27)
					(thickness 0.15)
				)
				(justify left bottom)
				(hide yes)
			)
		)
		(property "Datasheet" ""
			(at 240.03 223.52 0)
			(effects
				(font
					(size 1.27 1.27)
					(thickness 0.15)
				)
				(justify left bottom)
				(hide yes)
			)
		)
		(property "Description" ""
			(at 224.79 213.36 0)
			(effects
				(font
					(size 1.27 1.27)
				)
				(hide yes)
			)
		)
		(property "Author" "Antmicro"
			(at 240.03 215.9 0)
			(effects
				(font
					(size 1.27 1.27)
					(thickness 0.15)
				)
				(justify left bottom)
				(hide yes)
			)
		)
		(property "License" "Apache-2.0"
			(at 240.03 218.44 0)
			(effects
				(font
					(size 1.27 1.27)
					(thickness 0.15)
				)
				(justify left bottom)
				(hide yes)
			)
		)
		(pin "1"
		)
		(instances
			(project "data-center-rdimm-ddr5-tester"
				(path ""
					(reference "#PWR0178")
					(unit 1)
				)
			)
		)
	)
	(symbol
		(lib_id "antmicropower:GND")
		(at 313.69 234.95 0)
		(mirror y)
		(unit 1)
		(exclude_from_sim no)
		(in_bom yes)
		(on_board yes)
		(dnp no)
		(property "Reference" "#PWR0177"
			(at 313.69 241.3 0)
			(effects
				(font
					(size 1.27 1.27)
				)
				(hide yes)
			)
		)
		(property "Value" "GND"
			(at 315.595 239.395 0)
			(effects
				(font
					(size 1.27 1.27)
					(thickness 0.15)
				)
				(justify left bottom)
			)
		)
		(property "Footprint" ""
			(at 304.8 242.57 0)
			(effects
				(font
					(size 1.27 1.27)
					(thickness 0.15)
				)
				(justify left bottom)
				(hide yes)
			)
		)
		(property "Datasheet" ""
			(at 304.8 247.65 0)
			(effects
				(font
					(size 1.27 1.27)
					(thickness 0.15)
				)
				(justify left bottom)
				(hide yes)
			)
		)
		(property "Description" ""
			(at 313.69 234.95 0)
			(effects
				(font
					(size 1.27 1.27)
				)
				(hide yes)
			)
		)
		(property "Author" "Antmicro"
			(at 304.8 240.03 0)
			(effects
				(font
					(size 1.27 1.27)
					(thickness 0.15)
				)
				(justify left bottom)
				(hide yes)
			)
		)
		(property "License" "Apache-2.0"
			(at 304.8 242.57 0)
			(effects
				(font
					(size 1.27 1.27)
					(thickness 0.15)
				)
				(justify left bottom)
				(hide yes)
			)
		)
		(pin "1"
		)
		(instances
			(project "data-center-rdimm-ddr5-tester"
				(path ""
					(reference "#PWR0177")
					(unit 1)
				)
			)
		)
	)
	(symbol
		(lib_id "antmicroResistors0402:R_4k7_0402")
		(at 54.61 226.06 270)
		(unit 1)
		(exclude_from_sim no)
		(in_bom yes)
		(on_board yes)
		(dnp no)
		(fields_autoplaced yes)
		(property "Reference" "R39"
			(at 57.15 227.33 90)
			(effects
				(font
					(size 1.27 1.27)
					(thickness 0.15)
				)
				(justify left)
			)
		)
		(property "Value" "R_4k7_0402"
			(at 41.91 246.38 0)
			(effects
				(font
					(size 1.27 1.27)
					(thickness 0.15)
				)
				(justify left bottom)
				(hide yes)
			)
		)
		(property "Footprint" "antmicro-footprints:R_0402_1005Metric"
			(at 39.37 246.38 0)
			(effects
				(font
					(size 1.27 1.27)
					(thickness 0.15)
				)
				(justify left bottom)
				(hide yes)
			)
		)
		(property "Datasheet" "https://www.bourns.com/docs/product-datasheets/cr.pdf"
			(at 36.83 246.38 0)
			(effects
				(font
					(size 1.27 1.27)
					(thickness 0.15)
				)
				(justify left bottom)
				(hide yes)
			)
		)
		(property "Description" ""
			(at 54.61 226.06 0)
			(effects
				(font
					(size 1.27 1.27)
				)
				(hide yes)
			)
		)
		(property "MPN" "CR0402-FX-4701GLF"
			(at 34.29 246.38 0)
			(effects
				(font
					(size 1.27 1.27)
					(thickness 0.15)
				)
				(justify left bottom)
				(hide yes)
			)
		)
		(property "Manufacturer" "Bourns"
			(at 31.75 246.38 0)
			(effects
				(font
					(size 1.27 1.27)
					(thickness 0.15)
				)
				(justify left bottom)
				(hide yes)
			)
		)
		(property "License" "Apache-2.0"
			(at 29.21 246.38 0)
			(effects
				(font
					(size 1.27 1.27)
					(thickness 0.15)
				)
				(justify left bottom)
				(hide yes)
			)
		)
		(property "Author" "Antmicro"
			(at 26.67 246.38 0)
			(effects
				(font
					(size 1.27 1.27)
					(thickness 0.15)
				)
				(justify left bottom)
				(hide yes)
			)
		)
		(property "Val" "4k7"
			(at 57.15 229.87 90)
			(effects
				(font
					(size 1.27 1.27)
					(thickness 0.15)
				)
				(justify left)
			)
		)
		(property "Tolerance" "1%"
			(at 44.45 246.38 0)
			(effects
				(font
					(size 1.27 1.27)
				)
				(justify left bottom)
				(hide yes)
			)
		)
		(pin "2"
		)
		(pin "1"
		)
		(instances
			(project "data-center-rdimm-ddr5-tester"
				(path ""
					(reference "R39")
					(unit 1)
				)
			)
		)
	)
)
